FILE_TYPE = MACRO_DRAWING;
SET COLOR_WIRE YELLOW;
SET COLOR_PROP ORANGE;
SET COLOR_DOT WHITE;
SET COLOR_ARC YELLOW;
SET COLOR_BODY GREEN;
SET COLOR_NOTE PURPLE;
SET PROP_DISPLAY VALUE;
SET PAGE_NUMBER P5;
FORCEADD RESISTOR..1
(-11000 6100);
FORCEPROP 1 LAST $LOCATION R175
J 2
(-11200 6100);
DISPLAY 1.212766 (-11200 6100);
PAINT GREEN (-11200 6100);
FORCEPROP 0 LAST CDS_LOCATION R175
J 0
(-10750 6200);
DISPLAY 1.021277 (-10750 6200);
DISPLAY INVISIBLE (-10750 6200);
FORCEPROP 0 LAST $SEC 1
J 0
(-10750 6200);
DISPLAY 0.680851 (-10750 6200);
PAINT MONO (-10750 6200);
DISPLAY INVISIBLE (-10750 6200);
FORCEPROP 0 LAST CDS_SEC 1
J 0
(-10750 6200);
DISPLAY 1.021277 (-10750 6200);
DISPLAY INVISIBLE (-10750 6200);
FORCEPROP 0 LASTPIN (-11100 6100) $PN 1
J 2
(-11110 6110);
DISPLAY 0.680851 (-11110 6110);
PAINT MONO (-11110 6110);
FORCEPROP 0 LASTPIN (-10850 6100) $PN 2
J 0
(-10840 6110);
DISPLAY 0.680851 (-10840 6110);
PAINT MONO (-10840 6110);
FORCEPROP 1 LAST PATH I100
J 0
(-11197 6205);
DISPLAY 1.212766 (-11197 6205);
PAINT GREEN (-11197 6205);
DISPLAY INVISIBLE (-11197 6205);
FORCEPROP 1 LAST TOLERANCE 1%
J 0
(-11197 6355);
DISPLAY 1.212766 (-11197 6355);
PAINT GREEN (-11197 6355);
DISPLAY INVISIBLE (-11197 6355);
FORCEPROP 1 LAST CLS_PN G155-133R0-01
J 0
(-11136 6300);
DISPLAY 1.212766 (-11136 6300);
PAINT GREEN (-11136 6300);
DISPLAY INVISIBLE (-11136 6300);
FORCEPROP 1 LAST CDS_LMAN_SYM_OUTLINE -50,50,100,-50
J 0
(-11000 6100);
DISPLAY 0.468085 (-11000 6100);
PAINT GREEN (-11000 6100);
DISPLAY INVISIBLE (-11000 6100);
FORCEPROP 2 LAST CDS_LIB passive
J 0
(-11000 6100);
DISPLAY INVISIBLE (-11000 6100);
FORCEPROP 1 LAST VALUE 33OHM
J 0
(-10761 6105);
DISPLAY 1.212766 (-10761 6105);
PAINT GREEN (-10761 6105);
FORCEPROP 0 LAST PACKAGE 0402
J 0
(-11050 6100);
DISPLAY 0.638298 (-11050 6100);
FORCEPROP 0 LAST NO_ASSY TRUE
J 0
(-10450 6150);
DISPLAY 0.638298 (-10450 6150);
DISPLAY BOTH (-10450 6150);
FORCEADD RESISTOR..1
(-11000 5850);
FORCEPROP 1 LAST $LOCATION R183
J 2
(-11200 5850);
DISPLAY 1.212766 (-11200 5850);
PAINT GREEN (-11200 5850);
FORCEPROP 0 LAST CDS_LOCATION R183
J 0
(-10750 5950);
DISPLAY 1.021277 (-10750 5950);
DISPLAY INVISIBLE (-10750 5950);
FORCEPROP 0 LAST $SEC 1
J 0
(-10750 5950);
DISPLAY 0.680851 (-10750 5950);
PAINT MONO (-10750 5950);
DISPLAY INVISIBLE (-10750 5950);
FORCEPROP 0 LAST CDS_SEC 1
J 0
(-10750 5950);
DISPLAY 1.021277 (-10750 5950);
DISPLAY INVISIBLE (-10750 5950);
FORCEPROP 0 LASTPIN (-11100 5850) $PN 1
J 2
(-11110 5860);
DISPLAY 0.680851 (-11110 5860);
PAINT MONO (-11110 5860);
FORCEPROP 0 LASTPIN (-10850 5850) $PN 2
J 0
(-10840 5860);
DISPLAY 0.680851 (-10840 5860);
PAINT MONO (-10840 5860);
FORCEPROP 1 LAST PATH I101
J 0
(-11197 5955);
DISPLAY 1.212766 (-11197 5955);
PAINT GREEN (-11197 5955);
DISPLAY INVISIBLE (-11197 5955);
FORCEPROP 1 LAST TOLERANCE 1%
J 0
(-11197 6105);
DISPLAY 1.212766 (-11197 6105);
PAINT GREEN (-11197 6105);
DISPLAY INVISIBLE (-11197 6105);
FORCEPROP 1 LAST CLS_PN G155-133R0-01
J 0
(-11136 6050);
DISPLAY 1.212766 (-11136 6050);
PAINT GREEN (-11136 6050);
DISPLAY INVISIBLE (-11136 6050);
FORCEPROP 2 LAST CDS_LIB passive
J 0
(-11000 5850);
DISPLAY INVISIBLE (-11000 5850);
FORCEPROP 1 LAST CDS_LMAN_SYM_OUTLINE -50,50,100,-50
J 0
(-11000 5850);
DISPLAY 0.468085 (-11000 5850);
PAINT GREEN (-11000 5850);
DISPLAY INVISIBLE (-11000 5850);
FORCEPROP 0 LAST NO_ASSY TRUE
J 0
(-10450 5900);
DISPLAY 0.638298 (-10450 5900);
DISPLAY BOTH (-10450 5900);
FORCEPROP 0 LAST PACKAGE 0402
J 0
(-11050 5850);
DISPLAY 0.638298 (-11050 5850);
FORCEPROP 1 LAST VALUE 33OHM
J 0
(-10761 5855);
DISPLAY 1.212766 (-10761 5855);
PAINT GREEN (-10761 5855);
FORCEADD RESISTOR..1
(-11000 6000);
FORCEPROP 1 LAST $LOCATION R176
J 2
(-11200 6000);
DISPLAY 1.212766 (-11200 6000);
PAINT GREEN (-11200 6000);
FORCEPROP 0 LAST CDS_LOCATION R176
J 0
(-10750 6100);
DISPLAY 1.021277 (-10750 6100);
DISPLAY INVISIBLE (-10750 6100);
FORCEPROP 0 LAST $SEC 1
J 0
(-10750 6100);
DISPLAY 0.680851 (-10750 6100);
PAINT MONO (-10750 6100);
DISPLAY INVISIBLE (-10750 6100);
FORCEPROP 0 LAST CDS_SEC 1
J 0
(-10750 6100);
DISPLAY 1.021277 (-10750 6100);
DISPLAY INVISIBLE (-10750 6100);
FORCEPROP 0 LASTPIN (-11100 6000) $PN 1
J 2
(-11110 6010);
DISPLAY 0.680851 (-11110 6010);
PAINT MONO (-11110 6010);
FORCEPROP 0 LASTPIN (-10850 6000) $PN 2
J 0
(-10840 6010);
DISPLAY 0.680851 (-10840 6010);
PAINT MONO (-10840 6010);
FORCEPROP 1 LAST PATH I102
J 0
(-11197 6105);
DISPLAY 1.212766 (-11197 6105);
PAINT GREEN (-11197 6105);
DISPLAY INVISIBLE (-11197 6105);
FORCEPROP 1 LAST TOLERANCE 1%
J 0
(-11197 6255);
DISPLAY 1.212766 (-11197 6255);
PAINT GREEN (-11197 6255);
DISPLAY INVISIBLE (-11197 6255);
FORCEPROP 1 LAST CLS_PN G155-133R0-01
J 0
(-11136 6200);
DISPLAY 1.212766 (-11136 6200);
PAINT GREEN (-11136 6200);
DISPLAY INVISIBLE (-11136 6200);
FORCEPROP 1 LAST CDS_LMAN_SYM_OUTLINE -50,50,100,-50
J 0
(-11000 6000);
DISPLAY 0.468085 (-11000 6000);
PAINT GREEN (-11000 6000);
DISPLAY INVISIBLE (-11000 6000);
FORCEPROP 2 LAST CDS_LIB passive
J 0
(-11000 6000);
DISPLAY INVISIBLE (-11000 6000);
FORCEPROP 0 LAST PACKAGE 0402
J 0
(-11050 6000);
DISPLAY 0.638298 (-11050 6000);
FORCEPROP 0 LAST NO_ASSY TRUE
J 0
(-10450 6050);
DISPLAY 0.638298 (-10450 6050);
DISPLAY BOTH (-10450 6050);
FORCEPROP 1 LAST VALUE 33OHM
J 0
(-10750 6000);
DISPLAY 1.212766 (-10750 6000);
PAINT GREEN (-10750 6000);
FORCEADD RESISTOR..1
(-11000 5750);
FORCEPROP 1 LAST $LOCATION R184
J 2
(-11200 5750);
DISPLAY 1.212766 (-11200 5750);
PAINT GREEN (-11200 5750);
FORCEPROP 0 LAST CDS_LOCATION R184
J 0
(-10750 5850);
DISPLAY 1.021277 (-10750 5850);
DISPLAY INVISIBLE (-10750 5850);
FORCEPROP 0 LAST $SEC 1
J 0
(-10750 5850);
DISPLAY 0.680851 (-10750 5850);
PAINT MONO (-10750 5850);
DISPLAY INVISIBLE (-10750 5850);
FORCEPROP 0 LAST CDS_SEC 1
J 0
(-10750 5850);
DISPLAY 1.021277 (-10750 5850);
DISPLAY INVISIBLE (-10750 5850);
FORCEPROP 0 LASTPIN (-11100 5750) $PN 1
J 2
(-11110 5760);
DISPLAY 0.680851 (-11110 5760);
PAINT MONO (-11110 5760);
FORCEPROP 0 LASTPIN (-10850 5750) $PN 2
J 0
(-10840 5760);
DISPLAY 0.680851 (-10840 5760);
PAINT MONO (-10840 5760);
FORCEPROP 1 LAST PATH I103
J 0
(-11197 5855);
DISPLAY 1.212766 (-11197 5855);
PAINT GREEN (-11197 5855);
DISPLAY INVISIBLE (-11197 5855);
FORCEPROP 1 LAST TOLERANCE 1%
J 0
(-11197 6005);
DISPLAY 1.212766 (-11197 6005);
PAINT GREEN (-11197 6005);
DISPLAY INVISIBLE (-11197 6005);
FORCEPROP 1 LAST CLS_PN G155-133R0-01
J 0
(-11136 5950);
DISPLAY 1.212766 (-11136 5950);
PAINT GREEN (-11136 5950);
DISPLAY INVISIBLE (-11136 5950);
FORCEPROP 2 LAST CDS_LIB passive
J 0
(-11000 5750);
DISPLAY INVISIBLE (-11000 5750);
FORCEPROP 1 LAST CDS_LMAN_SYM_OUTLINE -50,50,100,-50
J 0
(-11000 5750);
DISPLAY 0.468085 (-11000 5750);
PAINT GREEN (-11000 5750);
DISPLAY INVISIBLE (-11000 5750);
FORCEPROP 0 LAST PACKAGE 0402
J 0
(-11050 5700);
DISPLAY 0.638298 (-11050 5700);
FORCEPROP 0 LAST NO_ASSY TRUE
J 0
(-10450 5800);
DISPLAY 0.638298 (-10450 5800);
DISPLAY BOTH (-10450 5800);
FORCEPROP 1 LAST VALUE 33OHM
J 0
(-10761 5755);
DISPLAY 1.212766 (-10761 5755);
PAINT GREEN (-10761 5755);
FORCEADD OFFPAGE_BI..1
R 2
(-12700 6100);
FORCEPROP 2 LAST CDS_LIB cls
J 0
(-12700 6100);
PAINT MONO (-12700 6100);
DISPLAY INVISIBLE (-12700 6100);
FORCEPROP 1 LAST CDS_LMAN_SYM_OUTLINE -50,50,50,-50
J 2
(-12700 6100);
DISPLAY 0.468085 (-12700 6100);
PAINT GREEN (-12700 6100);
DISPLAY INVISIBLE (-12700 6100);
FORCEPROP 1 LAST BODY_TYPE COMMENT
J 2
(-12710 6235);
DISPLAY 0.808511 (-12710 6235);
PAINT GREEN (-12710 6235);
DISPLAY INVISIBLE (-12710 6235);
FORCEPROP 1 LAST OFFPAGE TRUE
J 2
(-12710 6155);
DISPLAY 0.808511 (-12710 6155);
PAINT GREEN (-12710 6155);
DISPLAY INVISIBLE (-12710 6155);
FORCEPROP 2 LAST PATH I104
J 0
(-12850 6150);
DISPLAY 1.021277 (-12850 6150);
DISPLAY INVISIBLE (-12850 6150);
FORCEPROP 2 LAST $XR1 16D4<> 
J 0
(-13098 6100);
DISPLAY 0.638298 (-13098 6100);
PAINT MONO (-13098 6100);
FORCEPROP 2 LAST $XR0 9K9<> 
J 0
(-12888 6100);
DISPLAY 0.638298 (-12888 6100);
PAINT MONO (-12888 6100);
FORCEADD OFFPAGE_IN..2
R 2
(-12700 6000);
FORCEPROP 2 LAST CDS_LIB cls
J 0
(-12700 6000);
DISPLAY INVISIBLE (-12700 6000);
FORCEPROP 1 LAST CDS_LMAN_SYM_OUTLINE -50,50,50,-50
J 2
(-12700 6000);
DISPLAY 0.468085 (-12700 6000);
PAINT GREEN (-12700 6000);
DISPLAY INVISIBLE (-12700 6000);
FORCEPROP 2 LAST PATH I105
J 0
(-12850 6050);
DISPLAY 1.021277 (-12850 6050);
DISPLAY INVISIBLE (-12850 6050);
FORCEPROP 1 LAST BODY_TYPE COMMENT
J 2
(-12710 6135);
DISPLAY 0.808511 (-12710 6135);
PAINT GREEN (-12710 6135);
DISPLAY INVISIBLE (-12710 6135);
FORCEPROP 1 LAST OFFPAGE TRUE
J 2
(-12710 6055);
DISPLAY 0.808511 (-12710 6055);
PAINT GREEN (-12710 6055);
DISPLAY INVISIBLE (-12710 6055);
FORCEPROP 2 LAST $XR1 16D4< 
J 0
(-13032 6000);
DISPLAY 0.638298 (-13032 6000);
PAINT MONO (-13032 6000);
FORCEPROP 2 LAST $XR0 9K9> 
J 0
(-12852 6000);
DISPLAY 0.638298 (-12852 6000);
PAINT MONO (-12852 6000);
FORCEADD OFFPAGE_BI..1
R 2
(-12700 5850);
FORCEPROP 2 LAST CDS_LIB cls
J 0
(-12700 5850);
PAINT MONO (-12700 5850);
DISPLAY INVISIBLE (-12700 5850);
FORCEPROP 1 LAST CDS_LMAN_SYM_OUTLINE -50,50,50,-50
J 2
(-12700 5850);
DISPLAY 0.468085 (-12700 5850);
PAINT GREEN (-12700 5850);
DISPLAY INVISIBLE (-12700 5850);
FORCEPROP 2 LAST PATH I106
J 0
(-12850 5900);
DISPLAY 1.021277 (-12850 5900);
DISPLAY INVISIBLE (-12850 5900);
FORCEPROP 1 LAST OFFPAGE TRUE
J 2
(-12710 5905);
DISPLAY 0.808511 (-12710 5905);
PAINT GREEN (-12710 5905);
DISPLAY INVISIBLE (-12710 5905);
FORCEPROP 1 LAST BODY_TYPE COMMENT
J 2
(-12710 5985);
DISPLAY 0.808511 (-12710 5985);
PAINT GREEN (-12710 5985);
DISPLAY INVISIBLE (-12710 5985);
FORCEPROP 2 LAST $XR0 24J16<> 
J 0
(-12950 5850);
DISPLAY 0.638298 (-12950 5850);
PAINT MONO (-12950 5850);
FORCEADD OFFPAGE_IN..2
R 2
(-12700 5750);
FORCEPROP 1 LAST CDS_LMAN_SYM_OUTLINE -50,50,50,-50
J 2
(-12700 5750);
DISPLAY 0.468085 (-12700 5750);
PAINT GREEN (-12700 5750);
DISPLAY INVISIBLE (-12700 5750);
FORCEPROP 2 LAST CDS_LIB cls
J 0
(-12700 5750);
DISPLAY INVISIBLE (-12700 5750);
FORCEPROP 2 LAST PATH I107
J 0
(-12850 5800);
DISPLAY 1.021277 (-12850 5800);
DISPLAY INVISIBLE (-12850 5800);
FORCEPROP 1 LAST OFFPAGE TRUE
J 2
(-12710 5805);
DISPLAY 0.808511 (-12710 5805);
PAINT GREEN (-12710 5805);
DISPLAY INVISIBLE (-12710 5805);
FORCEPROP 1 LAST BODY_TYPE COMMENT
J 2
(-12710 5885);
DISPLAY 0.808511 (-12710 5885);
PAINT GREEN (-12710 5885);
DISPLAY INVISIBLE (-12710 5885);
FORCEPROP 2 LAST $XR0 24J16> 
J 0
(-12914 5750);
DISPLAY 0.638298 (-12914 5750);
PAINT MONO (-12914 5750);
FORCEADD RESISTOR..1
(-11000 6250);
FORCEPROP 1 LAST $LOCATION R313
J 2
(-11200 6250);
DISPLAY 1.212766 (-11200 6250);
PAINT GREEN (-11200 6250);
FORCEPROP 0 LAST CDS_LOCATION R313
J 0
(-10800 6350);
DISPLAY 1.021277 (-10800 6350);
DISPLAY INVISIBLE (-10800 6350);
FORCEPROP 0 LAST $SEC 1
J 0
(-10800 6350);
DISPLAY 0.680851 (-10800 6350);
PAINT MONO (-10800 6350);
DISPLAY INVISIBLE (-10800 6350);
FORCEPROP 0 LAST CDS_SEC 1
J 0
(-10800 6350);
DISPLAY 1.021277 (-10800 6350);
DISPLAY INVISIBLE (-10800 6350);
FORCEPROP 0 LASTPIN (-11100 6250) $PN 1
J 2
(-11110 6260);
DISPLAY 0.680851 (-11110 6260);
PAINT MONO (-11110 6260);
FORCEPROP 0 LASTPIN (-10850 6250) $PN 2
J 0
(-10840 6260);
DISPLAY 0.680851 (-10840 6260);
PAINT MONO (-10840 6260);
FORCEPROP 1 LAST CLS_PN G155-100R0-J0
J 0
(-11136 6450);
DISPLAY 1.212766 (-11136 6450);
PAINT GREEN (-11136 6450);
DISPLAY INVISIBLE (-11136 6450);
FORCEPROP 1 LAST TOLERANCE -
J 0
(-11197 6505);
DISPLAY 1.212766 (-11197 6505);
PAINT GREEN (-11197 6505);
DISPLAY INVISIBLE (-11197 6505);
FORCEPROP 2 LAST CDS_LIB passive
J 0
(-11000 6250);
DISPLAY INVISIBLE (-11000 6250);
FORCEPROP 1 LAST CDS_LMAN_SYM_OUTLINE -50,50,100,-50
J 0
(-11000 6250);
DISPLAY 0.468085 (-11000 6250);
PAINT GREEN (-11000 6250);
DISPLAY INVISIBLE (-11000 6250);
FORCEPROP 1 LAST PATH I111
J 0
(-11197 6355);
DISPLAY 1.212766 (-11197 6355);
PAINT GREEN (-11197 6355);
DISPLAY INVISIBLE (-11197 6355);
FORCEPROP 1 LAST VALUE 0OHM
J 0
(-10750 6250);
DISPLAY 1.234043 (-10750 6250);
PAINT GREEN (-10750 6250);
FORCEPROP 0 LAST PACKAGE 0402
J 0
(-11050 6250);
DISPLAY 0.638298 (-11050 6250);
FORCEADD RESISTOR..1
(-11000 6350);
FORCEPROP 1 LAST $LOCATION R312
J 2
(-11200 6350);
DISPLAY 1.212766 (-11200 6350);
PAINT GREEN (-11200 6350);
FORCEPROP 0 LAST CDS_LOCATION R312
J 0
(-10800 6450);
DISPLAY 1.021277 (-10800 6450);
DISPLAY INVISIBLE (-10800 6450);
FORCEPROP 0 LAST $SEC 1
J 0
(-10800 6450);
DISPLAY 0.680851 (-10800 6450);
PAINT MONO (-10800 6450);
DISPLAY INVISIBLE (-10800 6450);
FORCEPROP 0 LAST CDS_SEC 1
J 0
(-10800 6450);
DISPLAY 1.021277 (-10800 6450);
DISPLAY INVISIBLE (-10800 6450);
FORCEPROP 0 LASTPIN (-11100 6350) $PN 1
J 2
(-11110 6360);
DISPLAY 0.680851 (-11110 6360);
PAINT MONO (-11110 6360);
FORCEPROP 0 LASTPIN (-10850 6350) $PN 2
J 0
(-10840 6360);
DISPLAY 0.680851 (-10840 6360);
PAINT MONO (-10840 6360);
FORCEPROP 1 LAST CLS_PN G155-100R0-J0
J 0
(-11136 6550);
DISPLAY 1.212766 (-11136 6550);
PAINT GREEN (-11136 6550);
DISPLAY INVISIBLE (-11136 6550);
FORCEPROP 1 LAST TOLERANCE -
J 0
(-11197 6605);
DISPLAY 1.212766 (-11197 6605);
PAINT GREEN (-11197 6605);
DISPLAY INVISIBLE (-11197 6605);
FORCEPROP 1 LAST CDS_LMAN_SYM_OUTLINE -50,50,100,-50
J 0
(-11000 6350);
DISPLAY 0.468085 (-11000 6350);
PAINT GREEN (-11000 6350);
DISPLAY INVISIBLE (-11000 6350);
FORCEPROP 2 LAST CDS_LIB passive
J 0
(-11000 6350);
DISPLAY INVISIBLE (-11000 6350);
FORCEPROP 1 LAST PATH I112
J 0
(-11197 6455);
DISPLAY 1.212766 (-11197 6455);
PAINT GREEN (-11197 6455);
DISPLAY INVISIBLE (-11197 6455);
FORCEPROP 1 LAST VALUE 0OHM
J 0
(-10750 6350);
DISPLAY 1.234043 (-10750 6350);
PAINT GREEN (-10750 6350);
FORCEPROP 0 LAST PACKAGE 0402
J 0
(-11050 6350);
DISPLAY 0.638298 (-11050 6350);
FORCEADD OFFPAGE_OUT..1
R 2
(-12700 6250);
FORCEPROP 1 LAST OFFPAGE TRUE
J 2
(-12710 6305);
DISPLAY 0.808511 (-12710 6305);
PAINT GREEN (-12710 6305);
DISPLAY INVISIBLE (-12710 6305);
FORCEPROP 2 LAST CDS_LIB cls
J 0
(-12700 6250);
DISPLAY INVISIBLE (-12700 6250);
FORCEPROP 1 LAST CDS_LMAN_SYM_OUTLINE -50,50,50,-50
J 2
(-12700 6250);
DISPLAY 0.468085 (-12700 6250);
PAINT GREEN (-12700 6250);
DISPLAY INVISIBLE (-12700 6250);
FORCEPROP 1 LAST BODY_TYPE COMMENT
J 2
(-12710 6385);
DISPLAY 0.808511 (-12710 6385);
PAINT GREEN (-12710 6385);
DISPLAY INVISIBLE (-12710 6385);
FORCEPROP 2 LAST PATH I113
J 0
(-12650 6350);
DISPLAY 1.021277 (-12650 6350);
DISPLAY INVISIBLE (-12650 6350);
FORCEPROP 2 LAST $XR1 26K2< 
J 0
(-13063 6250);
DISPLAY 0.638298 (-13063 6250);
PAINT MONO (-13063 6250);
FORCEPROP 2 LAST $XR0 16D4> 
J 0
(-12883 6250);
DISPLAY 0.638298 (-12883 6250);
PAINT MONO (-12883 6250);
FORCEADD OFFPAGE_BI..1
R 2
(-12700 6350);
FORCEPROP 1 LAST OFFPAGE TRUE
J 2
(-12710 6405);
DISPLAY 0.808511 (-12710 6405);
PAINT GREEN (-12710 6405);
DISPLAY INVISIBLE (-12710 6405);
FORCEPROP 2 LAST CDS_LIB cls
J 0
(-12700 6350);
PAINT MONO (-12700 6350);
DISPLAY INVISIBLE (-12700 6350);
FORCEPROP 1 LAST CDS_LMAN_SYM_OUTLINE -50,50,50,-50
J 2
(-12700 6350);
DISPLAY 0.468085 (-12700 6350);
PAINT GREEN (-12700 6350);
DISPLAY INVISIBLE (-12700 6350);
FORCEPROP 1 LAST BODY_TYPE COMMENT
J 2
(-12710 6485);
DISPLAY 0.808511 (-12710 6485);
PAINT GREEN (-12710 6485);
DISPLAY INVISIBLE (-12710 6485);
FORCEPROP 2 LAST PATH I114
J 0
(-12850 6400);
DISPLAY 1.021277 (-12850 6400);
DISPLAY INVISIBLE (-12850 6400);
FORCEPROP 2 LAST $XR0 16D4<> 
J 0
(-12919 6350);
DISPLAY 0.638298 (-12919 6350);
PAINT MONO (-12919 6350);
FORCEPROP 2 LAST $XR1 26K2<> 
J 0
(-13129 6350);
DISPLAY 0.638298 (-13129 6350);
PAINT MONO (-13129 6350);
FORCEADD RESISTOR..1
(-9750 9800);
FORCEPROP 1 LAST $LOCATION R311
J 2
(-9900 9800);
DISPLAY 1.212766 (-9900 9800);
PAINT GREEN (-9900 9800);
FORCEPROP 0 LAST CDS_LOCATION R311
J 0
(-9550 9900);
DISPLAY 1.021277 (-9550 9900);
DISPLAY INVISIBLE (-9550 9900);
FORCEPROP 0 LAST $SEC 1
J 0
(-9550 9900);
DISPLAY 0.680851 (-9550 9900);
PAINT MONO (-9550 9900);
DISPLAY INVISIBLE (-9550 9900);
FORCEPROP 0 LAST CDS_SEC 1
J 0
(-9550 9900);
DISPLAY 1.021277 (-9550 9900);
DISPLAY INVISIBLE (-9550 9900);
FORCEPROP 0 LASTPIN (-9850 9800) $PN 1
J 2
(-9860 9810);
DISPLAY 0.680851 (-9860 9810);
PAINT MONO (-9860 9810);
FORCEPROP 0 LASTPIN (-9600 9800) $PN 2
J 0
(-9590 9810);
DISPLAY 0.680851 (-9590 9810);
PAINT MONO (-9590 9810);
FORCEPROP 1 LAST PATH I115
J 0
(-9947 9905);
DISPLAY 1.212766 (-9947 9905);
PAINT GREEN (-9947 9905);
DISPLAY INVISIBLE (-9947 9905);
FORCEPROP 2 LAST CDS_LIB passive
J 0
(-9750 9800);
DISPLAY INVISIBLE (-9750 9800);
FORCEPROP 1 LAST CDS_LMAN_SYM_OUTLINE -50,50,100,-50
J 0
(-9750 9800);
DISPLAY 0.468085 (-9750 9800);
PAINT GREEN (-9750 9800);
DISPLAY INVISIBLE (-9750 9800);
FORCEPROP 1 LAST TOLERANCE -
J 0
(-9947 10055);
DISPLAY 1.212766 (-9947 10055);
PAINT GREEN (-9947 10055);
DISPLAY INVISIBLE (-9947 10055);
FORCEPROP 1 LAST CLS_PN G155-100R0-J0
J 0
(-9886 10000);
DISPLAY 1.212766 (-9886 10000);
PAINT GREEN (-9886 10000);
DISPLAY INVISIBLE (-9886 10000);
FORCEPROP 0 LAST PACKAGE 0402
J 0
(-9800 9850);
DISPLAY 0.808511 (-9800 9850);
FORCEPROP 1 LAST VALUE 0OHM
J 0
(-9550 9800);
DISPLAY 1.234043 (-9550 9800);
PAINT GREEN (-9550 9800);
FORCEADD RESISTOR..1
(-9750 9900);
FORCEPROP 1 LAST $LOCATION R310
J 2
(-9900 9900);
DISPLAY 1.212766 (-9900 9900);
PAINT GREEN (-9900 9900);
FORCEPROP 0 LAST CDS_LOCATION R310
J 0
(-9550 10000);
DISPLAY 1.021277 (-9550 10000);
DISPLAY INVISIBLE (-9550 10000);
FORCEPROP 0 LAST $SEC 1
J 0
(-9550 10000);
DISPLAY 0.680851 (-9550 10000);
PAINT MONO (-9550 10000);
DISPLAY INVISIBLE (-9550 10000);
FORCEPROP 0 LAST CDS_SEC 1
J 0
(-9550 10000);
DISPLAY 1.021277 (-9550 10000);
DISPLAY INVISIBLE (-9550 10000);
FORCEPROP 0 LASTPIN (-9850 9900) $PN 1
J 2
(-9860 9910);
DISPLAY 0.680851 (-9860 9910);
PAINT MONO (-9860 9910);
FORCEPROP 0 LASTPIN (-9600 9900) $PN 2
J 0
(-9590 9910);
DISPLAY 0.680851 (-9590 9910);
PAINT MONO (-9590 9910);
FORCEPROP 1 LAST PATH I116
J 0
(-9947 10005);
DISPLAY 1.212766 (-9947 10005);
PAINT GREEN (-9947 10005);
DISPLAY INVISIBLE (-9947 10005);
FORCEPROP 1 LAST CDS_LMAN_SYM_OUTLINE -50,50,100,-50
J 0
(-9750 9900);
DISPLAY 0.468085 (-9750 9900);
PAINT GREEN (-9750 9900);
DISPLAY INVISIBLE (-9750 9900);
FORCEPROP 2 LAST CDS_LIB passive
J 0
(-9750 9900);
DISPLAY INVISIBLE (-9750 9900);
FORCEPROP 1 LAST TOLERANCE -
J 0
(-9947 10155);
DISPLAY 1.212766 (-9947 10155);
PAINT GREEN (-9947 10155);
DISPLAY INVISIBLE (-9947 10155);
FORCEPROP 1 LAST CLS_PN G155-100R0-J0
J 0
(-9886 10100);
DISPLAY 1.212766 (-9886 10100);
PAINT GREEN (-9886 10100);
DISPLAY INVISIBLE (-9886 10100);
FORCEPROP 1 LAST VALUE 0OHM
J 0
(-9550 9900);
DISPLAY 1.234043 (-9550 9900);
PAINT GREEN (-9550 9900);
FORCEPROP 0 LAST PACKAGE 0402
J 0
(-9800 9950);
DISPLAY 0.808511 (-9800 9950);
FORCEADD OFFPAGE_OUT..1
R 2
(-11450 9800);
FORCEPROP 2 LAST CDS_LIB cls
J 0
(-11450 9800);
DISPLAY INVISIBLE (-11450 9800);
FORCEPROP 1 LAST CDS_LMAN_SYM_OUTLINE -50,50,50,-50
J 2
(-11450 9800);
DISPLAY 0.468085 (-11450 9800);
PAINT GREEN (-11450 9800);
DISPLAY INVISIBLE (-11450 9800);
FORCEPROP 1 LAST BODY_TYPE COMMENT
J 2
(-11460 9935);
DISPLAY 0.808511 (-11460 9935);
PAINT GREEN (-11460 9935);
DISPLAY INVISIBLE (-11460 9935);
FORCEPROP 1 LAST OFFPAGE TRUE
J 2
(-11460 9855);
DISPLAY 0.808511 (-11460 9855);
PAINT GREEN (-11460 9855);
DISPLAY INVISIBLE (-11460 9855);
FORCEPROP 2 LAST PATH I117
J 0
(-11400 9900);
DISPLAY 1.021277 (-11400 9900);
DISPLAY INVISIBLE (-11400 9900);
FORCEPROP 2 LAST $XR1 26K2< 
J 0
(-11813 9800);
DISPLAY 0.638298 (-11813 9800);
PAINT MONO (-11813 9800);
FORCEPROP 2 LAST $XR0 16H3> 
J 0
(-11633 9800);
DISPLAY 0.638298 (-11633 9800);
PAINT MONO (-11633 9800);
FORCEADD OFFPAGE_BI..1
R 2
(-11450 9900);
FORCEPROP 2 LAST CDS_LIB cls
J 0
(-11450 9900);
PAINT MONO (-11450 9900);
DISPLAY INVISIBLE (-11450 9900);
FORCEPROP 1 LAST CDS_LMAN_SYM_OUTLINE -50,50,50,-50
J 2
(-11450 9900);
DISPLAY 0.468085 (-11450 9900);
PAINT GREEN (-11450 9900);
DISPLAY INVISIBLE (-11450 9900);
FORCEPROP 1 LAST BODY_TYPE COMMENT
J 2
(-11460 10035);
DISPLAY 0.808511 (-11460 10035);
PAINT GREEN (-11460 10035);
DISPLAY INVISIBLE (-11460 10035);
FORCEPROP 1 LAST OFFPAGE TRUE
J 2
(-11460 9955);
DISPLAY 0.808511 (-11460 9955);
PAINT GREEN (-11460 9955);
DISPLAY INVISIBLE (-11460 9955);
FORCEPROP 2 LAST PATH I118
J 0
(-11600 9950);
DISPLAY 1.021277 (-11600 9950);
DISPLAY INVISIBLE (-11600 9950);
FORCEPROP 2 LAST $XR1 26K2<> 
J 0
(-11879 9900);
DISPLAY 0.638298 (-11879 9900);
PAINT MONO (-11879 9900);
FORCEPROP 2 LAST $XR0 16H3<> 
J 0
(-11669 9900);
DISPLAY 0.638298 (-11669 9900);
PAINT MONO (-11669 9900);
FORCEADD OFFPAGE_IN..1
(-11450 10800);
FORCEPROP 1 LAST CDS_LMAN_SYM_OUTLINE -50,50,50,-50
J 0
(-11450 10800);
DISPLAY 0.468085 (-11450 10800);
PAINT GREEN (-11450 10800);
DISPLAY INVISIBLE (-11450 10800);
FORCEPROP 2 LAST CDS_LIB cls
J 0
(-11450 10800);
DISPLAY INVISIBLE (-11450 10800);
FORCEPROP 2 LAST PATH I124
J 0
(-11600 10850);
DISPLAY 1.021277 (-11600 10850);
DISPLAY INVISIBLE (-11600 10850);
FORCEPROP 1 LAST OFFPAGE TRUE
J 0
(-11440 10855);
DISPLAY 0.808511 (-11440 10855);
PAINT GREEN (-11440 10855);
DISPLAY INVISIBLE (-11440 10855);
FORCEPROP 1 LAST BODY_TYPE COMMENT
J 0
(-11440 10935);
DISPLAY 0.808511 (-11440 10935);
PAINT GREEN (-11440 10935);
DISPLAY INVISIBLE (-11440 10935);
FORCEPROP 2 LAST $XR0 11G5> 
J 0
(-11633 10800);
DISPLAY 0.638298 (-11633 10800);
PAINT MONO (-11633 10800);
FORCEADD RESISTOR..1
(-9750 10800);
FORCEPROP 1 LAST $LOCATION R60
J 2
(-9950 10800);
DISPLAY 1.212766 (-9950 10800);
PAINT GREEN (-9950 10800);
FORCEPROP 0 LAST CDS_LOCATION R60
J 0
(-9550 10900);
DISPLAY 1.021277 (-9550 10900);
DISPLAY INVISIBLE (-9550 10900);
FORCEPROP 0 LAST $SEC 1
J 0
(-9550 10900);
DISPLAY 0.680851 (-9550 10900);
PAINT MONO (-9550 10900);
DISPLAY INVISIBLE (-9550 10900);
FORCEPROP 0 LAST CDS_SEC 1
J 0
(-9550 10900);
DISPLAY 1.021277 (-9550 10900);
DISPLAY INVISIBLE (-9550 10900);
FORCEPROP 0 LASTPIN (-9850 10800) $PN 1
J 2
(-9860 10810);
DISPLAY 0.680851 (-9860 10810);
PAINT MONO (-9860 10810);
FORCEPROP 0 LASTPIN (-9600 10800) $PN 2
J 0
(-9590 10810);
DISPLAY 0.680851 (-9590 10810);
PAINT MONO (-9590 10810);
FORCEPROP 2 LAST CDS_LIB passive
J 0
(-9750 10800);
DISPLAY INVISIBLE (-9750 10800);
FORCEPROP 1 LAST CDS_LMAN_SYM_OUTLINE -50,50,100,-50
J 0
(-9750 10800);
DISPLAY 0.468085 (-9750 10800);
PAINT GREEN (-9750 10800);
DISPLAY INVISIBLE (-9750 10800);
FORCEPROP 2 LAST SIGNAL_MODEL DEFAULT_RESISTOR_33OHM_2_1
J 0
(-9900 11000);
DISPLAY 1.021277 (-9900 11000);
DISPLAY INVISIBLE (-9900 11000);
FORCEPROP 1 LAST CLS_PN G155-133R0-01
J 0
(-9886 11000);
DISPLAY 1.212766 (-9886 11000);
PAINT GREEN (-9886 11000);
DISPLAY INVISIBLE (-9886 11000);
FORCEPROP 1 LAST TOLERANCE 1%
J 0
(-9947 11055);
DISPLAY 1.212766 (-9947 11055);
PAINT GREEN (-9947 11055);
DISPLAY INVISIBLE (-9947 11055);
FORCEPROP 1 LAST PATH I125
J 0
(-9947 10905);
DISPLAY 1.212766 (-9947 10905);
PAINT GREEN (-9947 10905);
DISPLAY INVISIBLE (-9947 10905);
FORCEPROP 0 LAST PACKAGE 0402
J 0
(-9200 10800);
DISPLAY 0.808511 (-9200 10800);
FORCEPROP 1 LAST VALUE 33OHM
J 0
(-9550 10800);
DISPLAY 1.234043 (-9550 10800);
PAINT GREEN (-9550 10800);
FORCEADD CONN_HDR_2X2_M_S_SMT..1
R 2
(-10150 9450);
FORCEPROP 1 LAST LOCATION J9
J 2
(-10350 9050);
DISPLAY 1.212766 (-10350 9050);
PAINT GREEN (-10350 9050);
FORCEPROP 0 LAST $SEC 1
J 0
(-10350 9050);
DISPLAY 0.680851 (-10350 9050);
PAINT MONO (-10350 9050);
DISPLAY INVISIBLE (-10350 9050);
FORCEPROP 0 LAST CDS_SEC 1
J 0
(-10350 9050);
DISPLAY 1.021277 (-10350 9050);
DISPLAY INVISIBLE (-10350 9050);
FORCEPROP 0 LASTPIN (-10050 9350) $PN 1
J 0
(-10040 9360);
DISPLAY 0.680851 (-10040 9360);
PAINT MONO (-10040 9360);
FORCEPROP 0 LASTPIN (-10550 9350) $PN 2
J 2
(-10560 9360);
DISPLAY 0.680851 (-10560 9360);
PAINT MONO (-10560 9360);
FORCEPROP 0 LASTPIN (-10050 9250) $PN 3
J 0
(-10040 9260);
DISPLAY 0.680851 (-10040 9260);
PAINT MONO (-10040 9260);
FORCEPROP 0 LASTPIN (-10550 9250) $PN 4
J 2
(-10560 9260);
DISPLAY 0.680851 (-10560 9260);
PAINT MONO (-10560 9260);
FORCEPROP 2 LASTPIN (-10050 9250) SIG_NAME UN$5$CONNHDR2X2MSSMT$I126$3
J 0
(-10040 9260);
DISPLAY 0.659574 (-10040 9260);
PAINT MONO (-10040 9260);
DISPLAY INVISIBLE (-10040 9260);
FORCEPROP 2 LASTPIN (-10050 9350) SIG_NAME UN$5$CONNHDR2X2MSSMT$I126$1
J 0
(-10040 9360);
DISPLAY 0.659574 (-10040 9360);
PAINT MONO (-10040 9360);
DISPLAY INVISIBLE (-10040 9360);
FORCEPROP 2 LAST CDS_LIB connector
J 2
(-10150 9450);
DISPLAY INVISIBLE (-10150 9450);
FORCEPROP 1 LAST CDS_LMAN_SYM_OUTLINE 0,0,300,-300
J 2
(-10150 9450);
DISPLAY 0.468085 (-10150 9450);
PAINT GREEN (-10150 9450);
DISPLAY INVISIBLE (-10150 9450);
FORCEPROP 1 LAST PATH I126
J 2
(-10200 9500);
DISPLAY 1.212766 (-10200 9500);
PAINT GREEN (-10200 9500);
DISPLAY INVISIBLE (-10200 9500);
FORCEPROP 1 LAST CLS_PN G200-10686-01
J 2
(-9700 8950);
DISPLAY 1.212766 (-9700 8950);
PAINT GREEN (-9700 8950);
FORCEPROP 0 LAST PART_NUMBER 95278-101A04LF
J 0
(-10450 8850);
DISPLAY 1.021277 (-10450 8850);
FORCEADD CONN_HDR_2X2_M_S_SMT..1
(-2450 5650);
FORCEPROP 1 LAST LOCATION J17
J 0
(-2450 5900);
DISPLAY 1.212766 (-2450 5900);
PAINT GREEN (-2450 5900);
FORCEPROP 0 LAST $SEC 1
J 0
(-2450 6000);
DISPLAY 0.680851 (-2450 6000);
PAINT MONO (-2450 6000);
DISPLAY INVISIBLE (-2450 6000);
FORCEPROP 0 LAST CDS_SEC 1
J 0
(-2450 6000);
DISPLAY 1.021277 (-2450 6000);
DISPLAY INVISIBLE (-2450 6000);
FORCEPROP 0 LASTPIN (-2550 5550) $PN 1
J 2
(-2560 5560);
DISPLAY 0.680851 (-2560 5560);
PAINT MONO (-2560 5560);
FORCEPROP 0 LASTPIN (-2050 5550) $PN 2
J 0
(-2040 5560);
DISPLAY 0.680851 (-2040 5560);
PAINT MONO (-2040 5560);
FORCEPROP 0 LASTPIN (-2550 5450) $PN 3
J 2
(-2560 5460);
DISPLAY 0.680851 (-2560 5460);
PAINT MONO (-2560 5460);
FORCEPROP 0 LASTPIN (-2050 5450) $PN 4
J 0
(-2040 5460);
DISPLAY 0.680851 (-2040 5460);
PAINT MONO (-2040 5460);
FORCEPROP 1 LAST CDS_LMAN_SYM_OUTLINE 0,0,300,-300
J 0
(-2450 5650);
DISPLAY 0.468085 (-2450 5650);
PAINT GREEN (-2450 5650);
DISPLAY INVISIBLE (-2450 5650);
FORCEPROP 2 LAST CDS_LIB connector
J 2
(-2450 5650);
DISPLAY INVISIBLE (-2450 5650);
FORCEPROP 1 LAST PATH I127
J 0
(-2400 5700);
DISPLAY 1.212766 (-2400 5700);
PAINT GREEN (-2400 5700);
DISPLAY INVISIBLE (-2400 5700);
FORCEPROP 1 LAST CLS_PN G200-10686-01
J 0
(-2450 5800);
DISPLAY 1.212766 (-2450 5800);
PAINT GREEN (-2450 5800);
FORCEPROP 0 LAST PART_NUMBER 95278-101A04LF
J 0
(-2450 5700);
DISPLAY 1.021277 (-2450 5700);
FORCEADD GND_SG..1
(-1950 5250);
FORCEPROP 3 LASTPIN (-1900 5300) SIG_NAME SG\g
J 0
(-1890 5310);
DISPLAY 0.659574 (-1890 5310);
PAINT MONO (-1890 5310);
DISPLAY INVISIBLE (-1890 5310);
FORCEPROP 0 LAST VOLTAGE 0
J 0
(-1850 5250);
DISPLAY 1.021277 (-1850 5250);
DISPLAY INVISIBLE (-1850 5250);
FORCEPROP 1 LAST CDS_LMAN_SYM_OUTLINE 0,0,100,-50
J 0
(-1950 5250);
DISPLAY 0.468085 (-1950 5250);
PAINT GREEN (-1950 5250);
DISPLAY INVISIBLE (-1950 5250);
FORCEPROP 2 LAST CDS_LIB cls
J 0
(-1950 5250);
DISPLAY INVISIBLE (-1950 5250);
FORCEPROP 1 LAST BODY_TYPE PLUMBING
J 0
(-1935 5235);
DISPLAY 0.808511 (-1935 5235);
PAINT GREEN (-1935 5235);
DISPLAY INVISIBLE (-1935 5235);
FORCEPROP 1 LAST PATH I128
J 0
(-1915 5250);
DISPLAY 0.808511 (-1915 5250);
PAINT GREEN (-1915 5250);
DISPLAY INVISIBLE (-1915 5250);
FORCEPROP 1 LAST HDL_POWER SG
J 1
(-1895 5155);
DISPLAY 0.808511 (-1895 5155);
PAINT GREEN (-1895 5155);
FORCEADD OFFPAGE_IN..2
R 2
(-12700 5550);
FORCEPROP 2 LAST PATH I129
J 0
(-12850 5600);
DISPLAY 1.021277 (-12850 5600);
DISPLAY INVISIBLE (-12850 5600);
FORCEPROP 2 LAST CDS_LIB cls
J 0
(-12700 5550);
DISPLAY INVISIBLE (-12700 5550);
FORCEPROP 1 LAST CDS_LMAN_SYM_OUTLINE -50,50,50,-50
J 2
(-12700 5550);
DISPLAY 0.468085 (-12700 5550);
PAINT GREEN (-12700 5550);
DISPLAY INVISIBLE (-12700 5550);
FORCEPROP 1 LAST BODY_TYPE COMMENT
J 2
(-12710 5685);
DISPLAY 0.808511 (-12710 5685);
PAINT GREEN (-12710 5685);
DISPLAY INVISIBLE (-12710 5685);
FORCEPROP 1 LAST OFFPAGE TRUE
J 2
(-12710 5605);
DISPLAY 0.808511 (-12710 5605);
PAINT GREEN (-12710 5605);
DISPLAY INVISIBLE (-12710 5605);
FORCEPROP 2 LAST $XR0 11D5> 
J 0
(-12883 5550);
DISPLAY 0.638298 (-12883 5550);
PAINT MONO (-12883 5550);
FORCEADD RESISTOR..1
(-11000 5550);
FORCEPROP 1 LAST $LOCATION R1
J 2
(-11250 5550);
DISPLAY 1.212766 (-11250 5550);
PAINT GREEN (-11250 5550);
FORCEPROP 0 LAST CDS_LOCATION R1
J 0
(-10750 5650);
DISPLAY 1.021277 (-10750 5650);
DISPLAY INVISIBLE (-10750 5650);
FORCEPROP 0 LAST $SEC 1
J 0
(-10750 5650);
DISPLAY 0.680851 (-10750 5650);
PAINT MONO (-10750 5650);
DISPLAY INVISIBLE (-10750 5650);
FORCEPROP 0 LAST CDS_SEC 1
J 0
(-10750 5650);
DISPLAY 1.021277 (-10750 5650);
DISPLAY INVISIBLE (-10750 5650);
FORCEPROP 0 LASTPIN (-11100 5550) $PN 1
J 2
(-11110 5560);
DISPLAY 0.680851 (-11110 5560);
PAINT MONO (-11110 5560);
FORCEPROP 0 LASTPIN (-10850 5550) $PN 2
J 0
(-10840 5560);
DISPLAY 0.680851 (-10840 5560);
PAINT MONO (-10840 5560);
FORCEPROP 2 LAST CDS_LIB passive
J 0
(-11000 5550);
DISPLAY INVISIBLE (-11000 5550);
FORCEPROP 1 LAST CDS_LMAN_SYM_OUTLINE -50,50,100,-50
J 0
(-11000 5550);
DISPLAY 0.468085 (-11000 5550);
PAINT GREEN (-11000 5550);
DISPLAY INVISIBLE (-11000 5550);
FORCEPROP 1 LAST TOLERANCE 1%
J 0
(-11197 5805);
DISPLAY 1.212766 (-11197 5805);
PAINT GREEN (-11197 5805);
DISPLAY INVISIBLE (-11197 5805);
FORCEPROP 1 LAST CLS_PN G155-13300-01
J 0
(-11136 5750);
DISPLAY 1.212766 (-11136 5750);
PAINT GREEN (-11136 5750);
DISPLAY INVISIBLE (-11136 5750);
FORCEPROP 1 LAST PATH I130
J 0
(-11197 5655);
DISPLAY 1.212766 (-11197 5655);
PAINT GREEN (-11197 5655);
DISPLAY INVISIBLE (-11197 5655);
FORCEPROP 0 LAST NO_ASSY TRUE
J 0
(-11200 5450);
DISPLAY 0.808511 (-11200 5450);
DISPLAY BOTH (-11200 5450);
FORCEPROP 0 LAST PACKAGE 0402
J 0
(-11050 5600);
DISPLAY 0.638298 (-11050 5600);
FORCEPROP 1 LAST VALUE 330OHM
J 0
(-10750 5550);
DISPLAY 1.212766 (-10750 5550);
PAINT GREEN (-10750 5550);
FORCEADD GND_SG..1
(-4250 3850);
FORCEPROP 3 LASTPIN (-4200 3900) SIG_NAME SG\g
J 0
(-4190 3910);
DISPLAY 0.659574 (-4190 3910);
PAINT MONO (-4190 3910);
DISPLAY INVISIBLE (-4190 3910);
FORCEPROP 2 LAST CDS_LIB cls
J 0
(-4250 3850);
DISPLAY INVISIBLE (-4250 3850);
FORCEPROP 1 LAST PATH I139
J 0
(-4215 3850);
DISPLAY 0.808511 (-4215 3850);
PAINT GREEN (-4215 3850);
DISPLAY INVISIBLE (-4215 3850);
FORCEPROP 1 LAST CDS_LMAN_SYM_OUTLINE 0,0,100,-50
J 0
(-4250 3850);
DISPLAY 0.468085 (-4250 3850);
PAINT GREEN (-4250 3850);
DISPLAY INVISIBLE (-4250 3850);
FORCEPROP 1 LAST BODY_TYPE PLUMBING
J 0
(-4235 3835);
DISPLAY 0.808511 (-4235 3835);
PAINT GREEN (-4235 3835);
DISPLAY INVISIBLE (-4235 3835);
FORCEPROP 1 LAST HDL_POWER SG
J 1
(-4195 3755);
DISPLAY 0.808511 (-4195 3755);
PAINT GREEN (-4195 3755);
FORCEADD GND_SG..1
(-2400 3700);
FORCEPROP 3 LASTPIN (-2350 3750) SIG_NAME SG\g
J 0
(-2340 3760);
DISPLAY 0.659574 (-2340 3760);
PAINT MONO (-2340 3760);
DISPLAY INVISIBLE (-2340 3760);
FORCEPROP 2 LAST CDS_LIB cls
J 0
(-2400 3700);
DISPLAY INVISIBLE (-2400 3700);
FORCEPROP 1 LAST PATH I147
J 0
(-2365 3700);
DISPLAY 0.808511 (-2365 3700);
PAINT GREEN (-2365 3700);
DISPLAY INVISIBLE (-2365 3700);
FORCEPROP 1 LAST CDS_LMAN_SYM_OUTLINE 0,0,100,-50
J 0
(-2400 3700);
DISPLAY 0.468085 (-2400 3700);
PAINT GREEN (-2400 3700);
DISPLAY INVISIBLE (-2400 3700);
FORCEPROP 1 LAST BODY_TYPE PLUMBING
J 0
(-2385 3685);
DISPLAY 0.808511 (-2385 3685);
PAINT GREEN (-2385 3685);
DISPLAY INVISIBLE (-2385 3685);
FORCEPROP 1 LAST HDL_POWER SG
J 1
(-2345 3605);
DISPLAY 0.808511 (-2345 3605);
PAINT GREEN (-2345 3605);
FORCEADD 24LC16BT_I_ST_TSSOP8..2
(-2550 4450);
FORCEPROP 1 LAST $LOCATION U19
J 2
(-2600 3950);
DISPLAY 1.212766 (-2600 3950);
PAINT GREEN (-2600 3950);
FORCEPROP 0 LAST CDS_LOCATION U19
J 0
(-2600 4050);
DISPLAY 1.021277 (-2600 4050);
DISPLAY INVISIBLE (-2600 4050);
FORCEPROP 0 LAST $SEC 2
J 0
(-2600 4050);
DISPLAY 0.680851 (-2600 4050);
PAINT MONO (-2600 4050);
DISPLAY INVISIBLE (-2600 4050);
FORCEPROP 0 LAST CDS_SEC 2
J 0
(-2600 4050);
DISPLAY 1.021277 (-2600 4050);
DISPLAY INVISIBLE (-2600 4050);
FORCEPROP 0 LASTPIN (-2350 4550) $PN 8
R 1
J 0
(-2360 4560);
DISPLAY 0.680851 (-2360 4560);
PAINT MONO (-2360 4560);
FORCEPROP 0 LASTPIN (-2350 3850) $PN 4
R 1
J 2
(-2360 3840);
DISPLAY 0.680851 (-2360 3840);
PAINT MONO (-2360 3840);
FORCEPROP 1 LAST CDS_LMAN_SYM_OUTLINE 0,0,400,-500
J 0
(-2550 4450);
DISPLAY 0.468085 (-2550 4450);
PAINT GREEN (-2550 4450);
DISPLAY INVISIBLE (-2550 4450);
FORCEPROP 1 LAST PATH I148
J 2
(-2600 4500);
DISPLAY 1.212766 (-2600 4500);
PAINT GREEN (-2600 4500);
DISPLAY INVISIBLE (-2600 4500);
FORCEPROP 2 LAST CDS_LIB memory
J 0
(-2550 4450);
DISPLAY INVISIBLE (-2550 4450);
FORCEPROP 1 LAST CLS_PN G221-10176-01
J 2
(-2400 3850);
DISPLAY 1.212766 (-2400 3850);
PAINT GREEN (-2400 3850);
FORCEADD 24LC16BT_I_ST_TSSOP8..1
(-5950 4700);
FORCEPROP 1 LAST $LOCATION U19
J 0
(-5950 4850);
DISPLAY 1.212766 (-5950 4850);
PAINT GREEN (-5950 4850);
FORCEPROP 0 LAST CDS_LOCATION U19
J 0
(-5950 4950);
DISPLAY 1.021277 (-5950 4950);
DISPLAY INVISIBLE (-5950 4950);
FORCEPROP 0 LAST $SEC 1
J 0
(-5950 4950);
DISPLAY 0.680851 (-5950 4950);
PAINT MONO (-5950 4950);
DISPLAY INVISIBLE (-5950 4950);
FORCEPROP 0 LAST CDS_SEC 1
J 0
(-5950 4950);
DISPLAY 1.021277 (-5950 4950);
DISPLAY INVISIBLE (-5950 4950);
FORCEPROP 0 LASTPIN (-5350 4600) $PN 1
J 0
(-5340 4610);
DISPLAY 0.680851 (-5340 4610);
PAINT MONO (-5340 4610);
FORCEPROP 0 LASTPIN (-5350 4500) $PN 2
J 0
(-5340 4510);
DISPLAY 0.680851 (-5340 4510);
PAINT MONO (-5340 4510);
FORCEPROP 0 LASTPIN (-5350 4400) $PN 3
J 0
(-5340 4410);
DISPLAY 0.680851 (-5340 4410);
PAINT MONO (-5340 4410);
FORCEPROP 0 LASTPIN (-6050 4500) $PN 6
J 2
(-6060 4510);
DISPLAY 0.680851 (-6060 4510);
PAINT MONO (-6060 4510);
FORCEPROP 0 LASTPIN (-6050 4600) $PN 5
J 2
(-6060 4610);
DISPLAY 0.680851 (-6060 4610);
PAINT MONO (-6060 4610);
FORCEPROP 0 LASTPIN (-6050 4300) $PN 7
J 2
(-6060 4310);
DISPLAY 0.680851 (-6060 4310);
PAINT MONO (-6060 4310);
FORCEPROP 2 LASTPIN (-5350 4400) SIG_NAME UN$5$24LC16BTISTTSSOP8$I151$A2
J 0
(-5340 4410);
DISPLAY 0.659574 (-5340 4410);
PAINT MONO (-5340 4410);
DISPLAY INVISIBLE (-5340 4410);
FORCEPROP 2 LASTPIN (-5350 4600) SIG_NAME UN$5$24LC16BTISTTSSOP8$I151$A0
J 0
(-5340 4610);
DISPLAY 0.659574 (-5340 4610);
PAINT MONO (-5340 4610);
DISPLAY INVISIBLE (-5340 4610);
FORCEPROP 2 LASTPIN (-5350 4500) SIG_NAME UN$5$24LC16BTISTTSSOP8$I151$A1
J 0
(-5340 4510);
DISPLAY 0.659574 (-5340 4510);
PAINT MONO (-5340 4510);
DISPLAY INVISIBLE (-5340 4510);
FORCEPROP 2 LAST CDS_LIB memory
J 0
(-5950 4700);
DISPLAY INVISIBLE (-5950 4700);
FORCEPROP 1 LAST PATH I151
J 0
(-5900 4750);
DISPLAY 1.212766 (-5900 4750);
PAINT GREEN (-5900 4750);
DISPLAY INVISIBLE (-5900 4750);
FORCEPROP 1 LAST CDS_LMAN_SYM_OUTLINE 0,0,500,-500
J 0
(-5950 4700);
DISPLAY 0.468085 (-5950 4700);
PAINT GREEN (-5950 4700);
DISPLAY INVISIBLE (-5950 4700);
FORCEPROP 2 LAST PART_NUMBER 24LC64T
J 0
(-5750 4850);
DISPLAY 1.021277 (-5750 4850);
FORCEPROP 1 LAST CLS_PN G221-10176-01
J 0
(-5950 4750);
DISPLAY 1.212766 (-5950 4750);
PAINT GREEN (-5950 4750);
FORCEADD RESISTOR..2
(-5100 4800);
FORCEPROP 1 LAST $LOCATION R158
J 0
(-5050 4650);
DISPLAY 1.212766 (-5050 4650);
PAINT GREEN (-5050 4650);
FORCEPROP 0 LAST CDS_LOCATION R158
J 0
(-5050 4950);
DISPLAY 1.021277 (-5050 4950);
DISPLAY INVISIBLE (-5050 4950);
FORCEPROP 0 LAST $SEC 1
J 0
(-5050 4950);
DISPLAY 0.680851 (-5050 4950);
PAINT MONO (-5050 4950);
DISPLAY INVISIBLE (-5050 4950);
FORCEPROP 0 LAST CDS_SEC 1
J 0
(-5050 4950);
DISPLAY 1.021277 (-5050 4950);
DISPLAY INVISIBLE (-5050 4950);
FORCEPROP 0 LASTPIN (-5100 4900) $PN 1
R 1
J 0
(-5110 4910);
DISPLAY 0.680851 (-5110 4910);
PAINT MONO (-5110 4910);
FORCEPROP 0 LASTPIN (-5100 4650) $PN 2
R 1
J 2
(-5110 4640);
DISPLAY 0.680851 (-5110 4640);
PAINT MONO (-5110 4640);
FORCEPROP 2 LAST CDS_LIB passive
J 0
(-5100 4800);
DISPLAY INVISIBLE (-5100 4800);
FORCEPROP 1 LAST CDS_LMAN_SYM_OUTLINE -50,50,50,-100
J 0
(-5100 4800);
DISPLAY 0.468085 (-5100 4800);
PAINT GREEN (-5100 4800);
DISPLAY INVISIBLE (-5100 4800);
FORCEPROP 1 LAST TOLERANCE 1%
J 0
(-5297 5055);
DISPLAY 1.212766 (-5297 5055);
PAINT GREEN (-5297 5055);
DISPLAY INVISIBLE (-5297 5055);
FORCEPROP 1 LAST PATH I153
J 0
(-5297 4905);
DISPLAY 1.212766 (-5297 4905);
PAINT GREEN (-5297 4905);
DISPLAY INVISIBLE (-5297 4905);
FORCEPROP 1 LAST CLS_PN G155-14701-01
J 0
(-5236 5000);
DISPLAY 1.212766 (-5236 5000);
PAINT GREEN (-5236 5000);
DISPLAY INVISIBLE (-5236 5000);
FORCEPROP 0 LAST PACKAGE 0402
J 0
(-5050 4900);
DISPLAY 0.808511 (-5050 4900);
FORCEPROP 1 LAST VALUE 4.7KOHM
J 0
(-5050 4800);
DISPLAY 0.978723 (-5050 4800);
PAINT GREEN (-5050 4800);
FORCEADD RESISTOR..2
(-5100 4200);
FORCEPROP 1 LAST $LOCATION R159
J 0
(-5050 4050);
DISPLAY 0.978723 (-5050 4050);
PAINT GREEN (-5050 4050);
FORCEPROP 0 LAST CDS_LOCATION R159
J 0
(-5050 4350);
DISPLAY 1.021277 (-5050 4350);
DISPLAY INVISIBLE (-5050 4350);
FORCEPROP 0 LAST $SEC 1
J 0
(-5050 4350);
DISPLAY 0.680851 (-5050 4350);
PAINT MONO (-5050 4350);
DISPLAY INVISIBLE (-5050 4350);
FORCEPROP 0 LAST CDS_SEC 1
J 0
(-5050 4350);
DISPLAY 1.021277 (-5050 4350);
DISPLAY INVISIBLE (-5050 4350);
FORCEPROP 0 LASTPIN (-5100 4300) $PN 1
R 1
J 0
(-5110 4310);
DISPLAY 0.680851 (-5110 4310);
PAINT MONO (-5110 4310);
FORCEPROP 0 LASTPIN (-5100 4050) $PN 2
R 1
J 2
(-5110 4040);
DISPLAY 0.680851 (-5110 4040);
PAINT MONO (-5110 4040);
FORCEPROP 2 LAST CDS_LIB passive
J 0
(-5100 4200);
DISPLAY INVISIBLE (-5100 4200);
FORCEPROP 1 LAST PATH I156
J 0
(-5297 4305);
DISPLAY 1.212766 (-5297 4305);
PAINT GREEN (-5297 4305);
DISPLAY INVISIBLE (-5297 4305);
FORCEPROP 1 LAST CDS_LMAN_SYM_OUTLINE -50,50,50,-100
J 0
(-5100 4200);
DISPLAY 0.468085 (-5100 4200);
PAINT GREEN (-5100 4200);
DISPLAY INVISIBLE (-5100 4200);
FORCEPROP 1 LAST CLS_PN G155-14701-01
J 0
(-5236 4400);
DISPLAY 1.212766 (-5236 4400);
PAINT GREEN (-5236 4400);
DISPLAY INVISIBLE (-5236 4400);
FORCEPROP 1 LAST TOLERANCE 1%
J 0
(-5297 4455);
DISPLAY 1.212766 (-5297 4455);
PAINT GREEN (-5297 4455);
DISPLAY INVISIBLE (-5297 4455);
FORCEPROP 1 LAST VALUE 4.7KOHM
J 0
(-5050 4200);
DISPLAY 0.787234 (-5050 4200);
PAINT GREEN (-5050 4200);
FORCEPROP 0 LAST NO_ASSY TRUE
J 0
(-5050 4150);
DISPLAY 0.638298 (-5050 4150);
DISPLAY BOTH (-5050 4150);
FORCEPROP 0 LAST PACKAGE 0402
J 0
(-5050 4300);
DISPLAY 0.808511 (-5050 4300);
FORCEADD VCC..1
(-4250 5050);
FORCEPROP 3 LASTPIN (-4200 5000) SIG_NAME XP3R3V_FPGA\g
J 0
(-4190 5010);
DISPLAY 0.659574 (-4190 5010);
PAINT MONO (-4190 5010);
DISPLAY INVISIBLE (-4190 5010);
FORCEPROP 2 LAST CDS_LIB cls
J 0
(-4250 5050);
DISPLAY INVISIBLE (-4250 5050);
FORCEPROP 1 LAST PATH I159
J 0
(-4215 5140);
DISPLAY 0.808511 (-4215 5140);
PAINT GREEN (-4215 5140);
DISPLAY INVISIBLE (-4215 5140);
FORCEPROP 1 LAST CDS_LMAN_SYM_OUTLINE -250,250,250,-250
J 0
(-4250 5050);
DISPLAY 0.468085 (-4250 5050);
PAINT GREEN (-4250 5050);
DISPLAY INVISIBLE (-4250 5050);
FORCEPROP 1 LAST BODY_TYPE PLUMBING
J 0
(-4295 5007);
DISPLAY 0.340426 (-4295 5007);
PAINT GREEN (-4295 5007);
DISPLAY INVISIBLE (-4295 5007);
FORCEPROP 1 LAST HDL_POWER XP3R3V_FPGA
J 1
(-4195 5105);
DISPLAY 1.021277 (-4195 5105);
PAINT GREEN (-4195 5105);
FORCEPROP 0 LAST VOLTAGE 3.3V
J 0
(-4500 5200);
DISPLAY 1.021277 (-4500 5200);
DISPLAY BOTH (-4500 5200);
FORCEADD RESISTOR..2
(-4650 4800);
FORCEPROP 1 LAST $LOCATION R160
J 0
(-4600 4650);
DISPLAY 1.212766 (-4600 4650);
PAINT GREEN (-4600 4650);
FORCEPROP 0 LAST CDS_LOCATION R160
J 0
(-4600 4950);
DISPLAY 1.021277 (-4600 4950);
DISPLAY INVISIBLE (-4600 4950);
FORCEPROP 0 LAST $SEC 1
J 0
(-4600 4950);
DISPLAY 0.680851 (-4600 4950);
PAINT MONO (-4600 4950);
DISPLAY INVISIBLE (-4600 4950);
FORCEPROP 0 LAST CDS_SEC 1
J 0
(-4600 4950);
DISPLAY 1.021277 (-4600 4950);
DISPLAY INVISIBLE (-4600 4950);
FORCEPROP 0 LASTPIN (-4650 4900) $PN 1
R 1
J 0
(-4660 4910);
DISPLAY 0.680851 (-4660 4910);
PAINT MONO (-4660 4910);
FORCEPROP 0 LASTPIN (-4650 4650) $PN 2
R 1
J 2
(-4660 4640);
DISPLAY 0.680851 (-4660 4640);
PAINT MONO (-4660 4640);
FORCEPROP 2 LAST CDS_LIB passive
J 0
(-4650 4800);
DISPLAY INVISIBLE (-4650 4800);
FORCEPROP 1 LAST CDS_LMAN_SYM_OUTLINE -50,50,50,-100
J 0
(-4650 4800);
DISPLAY 0.468085 (-4650 4800);
PAINT GREEN (-4650 4800);
DISPLAY INVISIBLE (-4650 4800);
FORCEPROP 1 LAST TOLERANCE 1%
J 0
(-4847 5055);
DISPLAY 1.212766 (-4847 5055);
PAINT GREEN (-4847 5055);
DISPLAY INVISIBLE (-4847 5055);
FORCEPROP 1 LAST PATH I160
J 0
(-4847 4905);
DISPLAY 1.212766 (-4847 4905);
PAINT GREEN (-4847 4905);
DISPLAY INVISIBLE (-4847 4905);
FORCEPROP 1 LAST CLS_PN G155-14701-01
J 0
(-4786 5000);
DISPLAY 1.212766 (-4786 5000);
PAINT GREEN (-4786 5000);
DISPLAY INVISIBLE (-4786 5000);
FORCEPROP 0 LAST PACKAGE 0402
J 0
(-4600 4900);
DISPLAY 0.808511 (-4600 4900);
FORCEPROP 0 LAST NO_ASSY TRUE
J 0
(-4600 4750);
DISPLAY 0.638298 (-4600 4750);
DISPLAY BOTH (-4600 4750);
FORCEPROP 1 LAST VALUE 4.7KOHM
J 0
(-4600 4800);
DISPLAY 0.978723 (-4600 4800);
PAINT GREEN (-4600 4800);
FORCEADD RESISTOR..2
(-4200 4800);
FORCEPROP 1 LAST $LOCATION R162
J 0
(-4150 4650);
DISPLAY 1.212766 (-4150 4650);
PAINT GREEN (-4150 4650);
FORCEPROP 0 LAST CDS_LOCATION R162
J 0
(-4150 4950);
DISPLAY 1.021277 (-4150 4950);
DISPLAY INVISIBLE (-4150 4950);
FORCEPROP 0 LAST $SEC 1
J 0
(-4150 4950);
DISPLAY 0.680851 (-4150 4950);
PAINT MONO (-4150 4950);
DISPLAY INVISIBLE (-4150 4950);
FORCEPROP 0 LAST CDS_SEC 1
J 0
(-4150 4950);
DISPLAY 1.021277 (-4150 4950);
DISPLAY INVISIBLE (-4150 4950);
FORCEPROP 0 LASTPIN (-4200 4900) $PN 1
R 1
J 0
(-4210 4910);
DISPLAY 0.680851 (-4210 4910);
PAINT MONO (-4210 4910);
FORCEPROP 0 LASTPIN (-4200 4650) $PN 2
R 1
J 2
(-4210 4640);
DISPLAY 0.680851 (-4210 4640);
PAINT MONO (-4210 4640);
FORCEPROP 1 LAST PATH I161
J 0
(-4397 4905);
DISPLAY 1.212766 (-4397 4905);
PAINT GREEN (-4397 4905);
DISPLAY INVISIBLE (-4397 4905);
FORCEPROP 1 LAST TOLERANCE 1%
J 0
(-4397 5055);
DISPLAY 1.212766 (-4397 5055);
PAINT GREEN (-4397 5055);
DISPLAY INVISIBLE (-4397 5055);
FORCEPROP 1 LAST CDS_LMAN_SYM_OUTLINE -50,50,50,-100
J 0
(-4200 4800);
DISPLAY 0.468085 (-4200 4800);
PAINT GREEN (-4200 4800);
DISPLAY INVISIBLE (-4200 4800);
FORCEPROP 2 LAST CDS_LIB passive
J 0
(-4200 4800);
DISPLAY INVISIBLE (-4200 4800);
FORCEPROP 1 LAST CLS_PN G155-14701-01
J 0
(-4336 5000);
DISPLAY 1.212766 (-4336 5000);
PAINT GREEN (-4336 5000);
DISPLAY INVISIBLE (-4336 5000);
FORCEPROP 0 LAST PACKAGE 0402
J 0
(-4150 4900);
DISPLAY 0.808511 (-4150 4900);
FORCEPROP 0 LAST NO_ASSY TRUE
J 0
(-4150 4750);
DISPLAY 0.638298 (-4150 4750);
DISPLAY BOTH (-4150 4750);
FORCEPROP 1 LAST VALUE 4.7KOHM
J 0
(-4150 4800);
DISPLAY 0.978723 (-4150 4800);
PAINT GREEN (-4150 4800);
FORCEADD RESISTOR..1
(-7500 4600);
FORCEPROP 1 LAST $LOCATION R45
J 2
(-7700 4600);
DISPLAY 1.212766 (-7700 4600);
PAINT GREEN (-7700 4600);
FORCEPROP 0 LAST CDS_LOCATION R45
J 0
(-7300 4700);
DISPLAY 1.021277 (-7300 4700);
DISPLAY INVISIBLE (-7300 4700);
FORCEPROP 0 LAST $SEC 1
J 0
(-7300 4700);
DISPLAY 0.680851 (-7300 4700);
PAINT MONO (-7300 4700);
DISPLAY INVISIBLE (-7300 4700);
FORCEPROP 0 LAST CDS_SEC 1
J 0
(-7300 4700);
DISPLAY 1.021277 (-7300 4700);
DISPLAY INVISIBLE (-7300 4700);
FORCEPROP 0 LASTPIN (-7600 4600) $PN 1
J 2
(-7610 4610);
DISPLAY 0.680851 (-7610 4610);
PAINT MONO (-7610 4610);
FORCEPROP 0 LASTPIN (-7350 4600) $PN 2
J 0
(-7340 4610);
DISPLAY 0.680851 (-7340 4610);
PAINT MONO (-7340 4610);
FORCEPROP 2 LAST CDS_LIB passive
J 0
(-7500 4600);
DISPLAY INVISIBLE (-7500 4600);
FORCEPROP 1 LAST PATH I162
J 0
(-7697 4705);
DISPLAY 1.212766 (-7697 4705);
PAINT GREEN (-7697 4705);
DISPLAY INVISIBLE (-7697 4705);
FORCEPROP 1 LAST CDS_LMAN_SYM_OUTLINE -50,50,100,-50
J 0
(-7500 4600);
DISPLAY 0.468085 (-7500 4600);
PAINT GREEN (-7500 4600);
DISPLAY INVISIBLE (-7500 4600);
FORCEPROP 1 LAST TOLERANCE 1%
J 0
(-7697 4855);
DISPLAY 1.212766 (-7697 4855);
PAINT GREEN (-7697 4855);
DISPLAY INVISIBLE (-7697 4855);
FORCEPROP 1 LAST CLS_PN G155-133R0-01
J 0
(-7636 4800);
DISPLAY 1.212766 (-7636 4800);
PAINT GREEN (-7636 4800);
DISPLAY INVISIBLE (-7636 4800);
FORCEPROP 1 LAST VALUE 33OHM
J 0
(-7300 4600);
DISPLAY 1.212766 (-7300 4600);
PAINT GREEN (-7300 4600);
FORCEPROP 0 LAST PACKAGE 0402
J 0
(-7550 4650);
DISPLAY 1.021277 (-7550 4650);
FORCEADD RESISTOR..2
(-4650 4200);
FORCEPROP 1 LAST $LOCATION R161
J 0
(-4600 4050);
DISPLAY 1.212766 (-4600 4050);
PAINT GREEN (-4600 4050);
FORCEPROP 0 LAST CDS_LOCATION R161
J 0
(-4600 4350);
DISPLAY 1.021277 (-4600 4350);
DISPLAY INVISIBLE (-4600 4350);
FORCEPROP 0 LAST $SEC 1
J 0
(-4600 4350);
DISPLAY 0.680851 (-4600 4350);
PAINT MONO (-4600 4350);
DISPLAY INVISIBLE (-4600 4350);
FORCEPROP 0 LAST CDS_SEC 1
J 0
(-4600 4350);
DISPLAY 1.021277 (-4600 4350);
DISPLAY INVISIBLE (-4600 4350);
FORCEPROP 0 LASTPIN (-4650 4300) $PN 1
R 1
J 0
(-4660 4310);
DISPLAY 0.680851 (-4660 4310);
PAINT MONO (-4660 4310);
FORCEPROP 0 LASTPIN (-4650 4050) $PN 2
R 1
J 2
(-4660 4040);
DISPLAY 0.680851 (-4660 4040);
PAINT MONO (-4660 4040);
FORCEPROP 1 LAST CLS_PN G155-14701-01
J 0
(-4786 4400);
DISPLAY 1.212766 (-4786 4400);
PAINT GREEN (-4786 4400);
DISPLAY INVISIBLE (-4786 4400);
FORCEPROP 1 LAST TOLERANCE 1%
J 0
(-4847 4455);
DISPLAY 1.212766 (-4847 4455);
PAINT GREEN (-4847 4455);
DISPLAY INVISIBLE (-4847 4455);
FORCEPROP 1 LAST CDS_LMAN_SYM_OUTLINE -50,50,50,-100
J 0
(-4650 4200);
DISPLAY 0.468085 (-4650 4200);
PAINT GREEN (-4650 4200);
DISPLAY INVISIBLE (-4650 4200);
FORCEPROP 1 LAST PATH I165
J 0
(-4847 4305);
DISPLAY 1.212766 (-4847 4305);
PAINT GREEN (-4847 4305);
DISPLAY INVISIBLE (-4847 4305);
FORCEPROP 2 LAST CDS_LIB passive
J 0
(-4650 4200);
DISPLAY INVISIBLE (-4650 4200);
FORCEPROP 0 LAST PACKAGE 0402
J 0
(-4600 4300);
DISPLAY 0.808511 (-4600 4300);
FORCEPROP 1 LAST VALUE 4.7KOHM
J 0
(-4600 4200);
DISPLAY 0.787234 (-4600 4200);
PAINT GREEN (-4600 4200);
FORCEADD RESISTOR..2
(-4200 4200);
FORCEPROP 1 LAST $LOCATION R163
J 0
(-4150 4050);
DISPLAY 1.212766 (-4150 4050);
PAINT GREEN (-4150 4050);
FORCEPROP 0 LAST CDS_LOCATION R163
J 0
(-4150 4350);
DISPLAY 1.021277 (-4150 4350);
DISPLAY INVISIBLE (-4150 4350);
FORCEPROP 0 LAST $SEC 1
J 0
(-4150 4350);
DISPLAY 0.680851 (-4150 4350);
PAINT MONO (-4150 4350);
DISPLAY INVISIBLE (-4150 4350);
FORCEPROP 0 LAST CDS_SEC 1
J 0
(-4150 4350);
DISPLAY 1.021277 (-4150 4350);
DISPLAY INVISIBLE (-4150 4350);
FORCEPROP 0 LASTPIN (-4200 4300) $PN 1
R 1
J 0
(-4210 4310);
DISPLAY 0.680851 (-4210 4310);
PAINT MONO (-4210 4310);
FORCEPROP 0 LASTPIN (-4200 4050) $PN 2
R 1
J 2
(-4210 4040);
DISPLAY 0.680851 (-4210 4040);
PAINT MONO (-4210 4040);
FORCEPROP 1 LAST CLS_PN G155-14701-01
J 0
(-4336 4400);
DISPLAY 1.212766 (-4336 4400);
PAINT GREEN (-4336 4400);
DISPLAY INVISIBLE (-4336 4400);
FORCEPROP 1 LAST TOLERANCE 1%
J 0
(-4397 4455);
DISPLAY 1.212766 (-4397 4455);
PAINT GREEN (-4397 4455);
DISPLAY INVISIBLE (-4397 4455);
FORCEPROP 1 LAST CDS_LMAN_SYM_OUTLINE -50,50,50,-100
J 0
(-4200 4200);
DISPLAY 0.468085 (-4200 4200);
PAINT GREEN (-4200 4200);
DISPLAY INVISIBLE (-4200 4200);
FORCEPROP 1 LAST PATH I166
J 0
(-4397 4305);
DISPLAY 1.212766 (-4397 4305);
PAINT GREEN (-4397 4305);
DISPLAY INVISIBLE (-4397 4305);
FORCEPROP 2 LAST CDS_LIB passive
J 0
(-4200 4200);
DISPLAY INVISIBLE (-4200 4200);
FORCEPROP 0 LAST PACKAGE 0402
J 0
(-4150 4300);
DISPLAY 0.808511 (-4150 4300);
FORCEPROP 1 LAST VALUE 4.7KOHM
J 0
(-4150 4200);
DISPLAY 0.787234 (-4150 4200);
PAINT GREEN (-4150 4200);
FORCEADD RESISTOR..2
(-8850 4000);
FORCEPROP 1 LAST $LOCATION R24
J 0
(-8800 3850);
DISPLAY 1.212766 (-8800 3850);
PAINT GREEN (-8800 3850);
FORCEPROP 0 LAST CDS_LOCATION R24
J 0
(-8800 4100);
DISPLAY 1.021277 (-8800 4100);
DISPLAY INVISIBLE (-8800 4100);
FORCEPROP 0 LAST $SEC 1
J 0
(-8800 4100);
DISPLAY 0.680851 (-8800 4100);
PAINT MONO (-8800 4100);
DISPLAY INVISIBLE (-8800 4100);
FORCEPROP 0 LAST CDS_SEC 1
J 0
(-8800 4100);
DISPLAY 1.021277 (-8800 4100);
DISPLAY INVISIBLE (-8800 4100);
FORCEPROP 0 LASTPIN (-8850 4100) $PN 1
R 1
J 0
(-8860 4110);
DISPLAY 0.680851 (-8860 4110);
PAINT MONO (-8860 4110);
FORCEPROP 0 LASTPIN (-8850 3850) $PN 2
R 1
J 2
(-8860 3840);
DISPLAY 0.680851 (-8860 3840);
PAINT MONO (-8860 3840);
FORCEPROP 1 LAST PATH I167
J 0
(-9047 4105);
DISPLAY 1.212766 (-9047 4105);
PAINT GREEN (-9047 4105);
DISPLAY INVISIBLE (-9047 4105);
FORCEPROP 1 LAST CLS_PN G155-14701-01
J 0
(-8986 4200);
DISPLAY 1.212766 (-8986 4200);
PAINT GREEN (-8986 4200);
DISPLAY INVISIBLE (-8986 4200);
FORCEPROP 1 LAST TOLERANCE 1%
J 0
(-9047 4255);
DISPLAY 1.212766 (-9047 4255);
PAINT GREEN (-9047 4255);
DISPLAY INVISIBLE (-9047 4255);
FORCEPROP 1 LAST CDS_LMAN_SYM_OUTLINE -50,50,50,-100
J 0
(-8850 4000);
DISPLAY 0.468085 (-8850 4000);
PAINT GREEN (-8850 4000);
DISPLAY INVISIBLE (-8850 4000);
FORCEPROP 2 LAST CDS_LIB passive
J 0
(-8850 4000);
DISPLAY INVISIBLE (-8850 4000);
FORCEPROP 1 LAST VALUE 4.7KOHM
J 0
(-8800 3950);
DISPLAY 0.978723 (-8800 3950);
PAINT GREEN (-8800 3950);
FORCEPROP 0 LAST PACKAGE 0402
J 0
(-8800 4050);
DISPLAY 0.808511 (-8800 4050);
FORCEADD VCC..1
(-8950 4950);
FORCEPROP 3 LASTPIN (-8900 4900) SIG_NAME XP3R3V_FPGA\g
J 0
(-8890 4910);
DISPLAY 0.659574 (-8890 4910);
PAINT MONO (-8890 4910);
DISPLAY INVISIBLE (-8890 4910);
FORCEPROP 1 LAST PATH I168
J 0
(-8915 5040);
DISPLAY 0.808511 (-8915 5040);
PAINT GREEN (-8915 5040);
DISPLAY INVISIBLE (-8915 5040);
FORCEPROP 2 LAST CDS_LIB cls
J 0
(-8950 4950);
DISPLAY INVISIBLE (-8950 4950);
FORCEPROP 1 LAST CDS_LMAN_SYM_OUTLINE -250,250,250,-250
J 0
(-8950 4950);
DISPLAY 0.468085 (-8950 4950);
PAINT GREEN (-8950 4950);
DISPLAY INVISIBLE (-8950 4950);
FORCEPROP 1 LAST BODY_TYPE PLUMBING
J 0
(-8995 4907);
DISPLAY 0.340426 (-8995 4907);
PAINT GREEN (-8995 4907);
DISPLAY INVISIBLE (-8995 4907);
FORCEPROP 1 LAST HDL_POWER XP3R3V_FPGA
J 1
(-8895 5005);
DISPLAY 1.021277 (-8895 5005);
PAINT GREEN (-8895 5005);
FORCEPROP 0 LAST VOLTAGE 3.3V
J 0
(-9200 5100);
DISPLAY 1.021277 (-9200 5100);
DISPLAY BOTH (-9200 5100);
FORCEADD RESISTOR..2
(-8900 4650);
FORCEPROP 1 LAST $LOCATION R3
J 0
(-8850 4500);
DISPLAY 1.212766 (-8850 4500);
PAINT GREEN (-8850 4500);
FORCEPROP 0 LAST CDS_LOCATION R3
J 0
(-8850 4750);
DISPLAY 1.021277 (-8850 4750);
DISPLAY INVISIBLE (-8850 4750);
FORCEPROP 0 LAST $SEC 1
J 0
(-8850 4750);
DISPLAY 0.680851 (-8850 4750);
PAINT MONO (-8850 4750);
DISPLAY INVISIBLE (-8850 4750);
FORCEPROP 0 LAST CDS_SEC 1
J 0
(-8850 4750);
DISPLAY 1.021277 (-8850 4750);
DISPLAY INVISIBLE (-8850 4750);
FORCEPROP 0 LASTPIN (-8900 4750) $PN 1
R 1
J 0
(-8910 4760);
DISPLAY 0.680851 (-8910 4760);
PAINT MONO (-8910 4760);
FORCEPROP 0 LASTPIN (-8900 4500) $PN 2
R 1
J 2
(-8910 4490);
DISPLAY 0.680851 (-8910 4490);
PAINT MONO (-8910 4490);
FORCEPROP 1 LAST CLS_PN G155-14701-01
J 0
(-9036 4850);
DISPLAY 1.212766 (-9036 4850);
PAINT GREEN (-9036 4850);
DISPLAY INVISIBLE (-9036 4850);
FORCEPROP 1 LAST TOLERANCE 1%
J 0
(-9097 4905);
DISPLAY 1.212766 (-9097 4905);
PAINT GREEN (-9097 4905);
DISPLAY INVISIBLE (-9097 4905);
FORCEPROP 1 LAST CDS_LMAN_SYM_OUTLINE -50,50,50,-100
J 0
(-8900 4650);
DISPLAY 0.468085 (-8900 4650);
PAINT GREEN (-8900 4650);
DISPLAY INVISIBLE (-8900 4650);
FORCEPROP 2 LAST CDS_LIB passive
J 0
(-8900 4650);
DISPLAY INVISIBLE (-8900 4650);
FORCEPROP 1 LAST PATH I169
J 0
(-9097 4755);
DISPLAY 1.212766 (-9097 4755);
PAINT GREEN (-9097 4755);
DISPLAY INVISIBLE (-9097 4755);
FORCEPROP 0 LAST PACKAGE 0402
J 0
(-8850 4700);
DISPLAY 0.808511 (-8850 4700);
FORCEPROP 1 LAST VALUE 4.7KOHM
J 0
(-8850 4600);
DISPLAY 0.978723 (-8850 4600);
PAINT GREEN (-8850 4600);
FORCEPROP 0 LAST NO_ASSY TRUE
J 0
(-9400 4600);
DISPLAY 0.808511 (-9400 4600);
DISPLAY BOTH (-9400 4600);
FORCEADD GND_SG..1
(-8900 3600);
FORCEPROP 3 LASTPIN (-8850 3650) SIG_NAME SG\g
J 0
(-8840 3660);
DISPLAY 0.659574 (-8840 3660);
PAINT MONO (-8840 3660);
DISPLAY INVISIBLE (-8840 3660);
FORCEPROP 1 LAST BODY_TYPE PLUMBING
J 0
(-8885 3585);
DISPLAY 0.808511 (-8885 3585);
PAINT GREEN (-8885 3585);
DISPLAY INVISIBLE (-8885 3585);
FORCEPROP 1 LAST CDS_LMAN_SYM_OUTLINE 0,0,100,-50
J 0
(-8900 3600);
DISPLAY 0.468085 (-8900 3600);
PAINT GREEN (-8900 3600);
DISPLAY INVISIBLE (-8900 3600);
FORCEPROP 2 LAST CDS_LIB cls
J 0
(-8900 3600);
DISPLAY INVISIBLE (-8900 3600);
FORCEPROP 1 LAST PATH I170
J 0
(-8865 3600);
DISPLAY 0.808511 (-8865 3600);
PAINT GREEN (-8865 3600);
DISPLAY INVISIBLE (-8865 3600);
FORCEPROP 1 LAST HDL_POWER SG
J 1
(-8845 3505);
DISPLAY 0.808511 (-8845 3505);
PAINT GREEN (-8845 3505);
FORCEADD CAPACITOR..2
(-1850 4250);
FORCEPROP 1 LAST $LOCATION C1
J 0
(-1800 4100);
DISPLAY 1.212766 (-1800 4100);
PAINT GREEN (-1800 4100);
FORCEPROP 0 LAST CDS_LOCATION C1
J 0
(-1800 4400);
DISPLAY 1.021277 (-1800 4400);
DISPLAY INVISIBLE (-1800 4400);
FORCEPROP 0 LAST $SEC 1
J 0
(-1800 4400);
DISPLAY 0.680851 (-1800 4400);
PAINT MONO (-1800 4400);
DISPLAY INVISIBLE (-1800 4400);
FORCEPROP 0 LAST CDS_SEC 1
J 0
(-1800 4400);
DISPLAY 1.021277 (-1800 4400);
DISPLAY INVISIBLE (-1800 4400);
FORCEPROP 0 LASTPIN (-1850 4350) $PN 1
R 1
J 0
(-1860 4360);
DISPLAY 0.680851 (-1860 4360);
PAINT MONO (-1860 4360);
FORCEPROP 0 LASTPIN (-1850 4100) $PN 2
R 1
J 2
(-1860 4090);
DISPLAY 0.680851 (-1860 4090);
PAINT MONO (-1860 4090);
FORCEPROP 1 LAST TOLERANCE 10%
J 0
(-2000 4350);
DISPLAY 1.212766 (-2000 4350);
PAINT GREEN (-2000 4350);
DISPLAY INVISIBLE (-2000 4350);
FORCEPROP 1 LAST CLS_PN G105-0B104-EK
J 0
(-1950 4300);
DISPLAY 1.212766 (-1950 4300);
PAINT GREEN (-1950 4300);
DISPLAY INVISIBLE (-1950 4300);
FORCEPROP 1 LAST CDS_LMAN_SYM_OUTLINE -50,0,50,-50
J 0
(-1850 4250);
DISPLAY 0.468085 (-1850 4250);
PAINT GREEN (-1850 4250);
DISPLAY INVISIBLE (-1850 4250);
FORCEPROP 1 LAST PATH I171
J 0
(-1950 4300);
DISPLAY 1.212766 (-1950 4300);
PAINT GREEN (-1950 4300);
DISPLAY INVISIBLE (-1950 4300);
FORCEPROP 2 LAST CDS_LIB passive
J 0
(-1850 4250);
DISPLAY INVISIBLE (-1850 4250);
FORCEPROP 0 LAST PACKAGE 0402
J 0
(-1700 4200);
DISPLAY 1.021277 (-1700 4200);
FORCEPROP 0 LAST VOLTAGE 25V
J 0
(-1750 4000);
DISPLAY 1.021277 (-1750 4000);
FORCEPROP 1 LAST VALUE 0.1UF
J 0
(-1800 4300);
DISPLAY 1.212766 (-1800 4300);
PAINT GREEN (-1800 4300);
FORCEADD VCC..1
(-2400 4700);
FORCEPROP 3 LASTPIN (-2350 4650) SIG_NAME XP3R3V_FPGA\g
J 0
(-2340 4660);
DISPLAY 0.659574 (-2340 4660);
PAINT MONO (-2340 4660);
DISPLAY INVISIBLE (-2340 4660);
FORCEPROP 1 LAST BODY_TYPE PLUMBING
J 0
(-2445 4657);
DISPLAY 0.340426 (-2445 4657);
PAINT GREEN (-2445 4657);
DISPLAY INVISIBLE (-2445 4657);
FORCEPROP 1 LAST CDS_LMAN_SYM_OUTLINE -250,250,250,-250
J 0
(-2400 4700);
DISPLAY 0.468085 (-2400 4700);
PAINT GREEN (-2400 4700);
DISPLAY INVISIBLE (-2400 4700);
FORCEPROP 1 LAST PATH I172
J 0
(-2365 4790);
DISPLAY 0.808511 (-2365 4790);
PAINT GREEN (-2365 4790);
DISPLAY INVISIBLE (-2365 4790);
FORCEPROP 2 LAST CDS_LIB cls
J 0
(-2400 4700);
DISPLAY INVISIBLE (-2400 4700);
FORCEPROP 0 LAST VOLTAGE 3.3V
J 0
(-2650 4850);
DISPLAY 1.021277 (-2650 4850);
DISPLAY BOTH (-2650 4850);
FORCEPROP 1 LAST HDL_POWER XP3R3V_FPGA
J 1
(-2345 4755);
DISPLAY 1.021277 (-2345 4755);
PAINT GREEN (-2345 4755);
FORCEADD RESISTOR..1
(-9750 4300);
FORCEPROP 1 LAST $LOCATION R2
J 2
(-9950 4300);
DISPLAY 1.212766 (-9950 4300);
PAINT GREEN (-9950 4300);
FORCEPROP 0 LAST CDS_LOCATION R2
J 0
(-9500 4400);
DISPLAY 1.021277 (-9500 4400);
DISPLAY INVISIBLE (-9500 4400);
FORCEPROP 0 LAST $SEC 1
J 0
(-9500 4400);
DISPLAY 0.680851 (-9500 4400);
PAINT MONO (-9500 4400);
DISPLAY INVISIBLE (-9500 4400);
FORCEPROP 0 LAST CDS_SEC 1
J 0
(-9500 4400);
DISPLAY 1.021277 (-9500 4400);
DISPLAY INVISIBLE (-9500 4400);
FORCEPROP 0 LASTPIN (-9850 4300) $PN 1
J 2
(-9860 4310);
DISPLAY 0.680851 (-9860 4310);
PAINT MONO (-9860 4310);
FORCEPROP 0 LASTPIN (-9600 4300) $PN 2
J 0
(-9590 4310);
DISPLAY 0.680851 (-9590 4310);
PAINT MONO (-9590 4310);
FORCEPROP 1 LAST CLS_PN G155-13300-01
J 0
(-9886 4500);
DISPLAY 1.212766 (-9886 4500);
PAINT GREEN (-9886 4500);
DISPLAY INVISIBLE (-9886 4500);
FORCEPROP 1 LAST TOLERANCE 1%
J 0
(-9947 4555);
DISPLAY 1.212766 (-9947 4555);
PAINT GREEN (-9947 4555);
DISPLAY INVISIBLE (-9947 4555);
FORCEPROP 1 LAST CDS_LMAN_SYM_OUTLINE -50,50,100,-50
J 0
(-9750 4300);
DISPLAY 0.468085 (-9750 4300);
PAINT GREEN (-9750 4300);
DISPLAY INVISIBLE (-9750 4300);
FORCEPROP 2 LAST CDS_LIB passive
J 0
(-9750 4300);
DISPLAY INVISIBLE (-9750 4300);
FORCEPROP 1 LAST PATH I173
J 0
(-9947 4405);
DISPLAY 1.212766 (-9947 4405);
PAINT GREEN (-9947 4405);
DISPLAY INVISIBLE (-9947 4405);
FORCEPROP 0 LAST PACKAGE 0402
J 0
(-9800 4350);
DISPLAY 0.808511 (-9800 4350);
FORCEPROP 1 LAST VALUE 330OHM
J 0
(-9500 4300);
DISPLAY 1.212766 (-9500 4300);
PAINT GREEN (-9500 4300);
FORCEADD OFFPAGE_IN..2
R 2
(-11450 4300);
FORCEPROP 2 LAST PATH I174
J 0
(-11600 4350);
DISPLAY 1.021277 (-11600 4350);
DISPLAY INVISIBLE (-11600 4350);
FORCEPROP 2 LAST CDS_LIB cls
J 0
(-11450 4300);
DISPLAY INVISIBLE (-11450 4300);
FORCEPROP 1 LAST CDS_LMAN_SYM_OUTLINE -50,50,50,-50
J 2
(-11450 4300);
DISPLAY 0.468085 (-11450 4300);
PAINT GREEN (-11450 4300);
DISPLAY INVISIBLE (-11450 4300);
FORCEPROP 1 LAST BODY_TYPE COMMENT
J 2
(-11460 4435);
DISPLAY 0.808511 (-11460 4435);
PAINT GREEN (-11460 4435);
DISPLAY INVISIBLE (-11460 4435);
FORCEPROP 1 LAST OFFPAGE TRUE
J 2
(-11460 4355);
DISPLAY 0.808511 (-11460 4355);
PAINT GREEN (-11460 4355);
DISPLAY INVISIBLE (-11460 4355);
FORCEPROP 2 LAST $XR0 11D5> 
J 0
(-11633 4300);
DISPLAY 0.638298 (-11633 4300);
PAINT MONO (-11633 4300);
FORCEADD OFFPAGE_BI..1
R 2
(-11450 9350);
FORCEPROP 1 LAST BODY_TYPE COMMENT
J 2
(-11460 9485);
DISPLAY 0.808511 (-11460 9485);
PAINT GREEN (-11460 9485);
DISPLAY INVISIBLE (-11460 9485);
FORCEPROP 1 LAST CDS_LMAN_SYM_OUTLINE -50,50,50,-50
J 2
(-11450 9350);
DISPLAY 0.468085 (-11450 9350);
PAINT GREEN (-11450 9350);
DISPLAY INVISIBLE (-11450 9350);
FORCEPROP 2 LAST CDS_LIB cls
J 0
(-11450 9350);
PAINT MONO (-11450 9350);
DISPLAY INVISIBLE (-11450 9350);
FORCEPROP 1 LAST OFFPAGE TRUE
J 2
(-11460 9405);
DISPLAY 0.808511 (-11460 9405);
PAINT GREEN (-11460 9405);
DISPLAY INVISIBLE (-11460 9405);
FORCEPROP 2 LAST PATH I175
J 0
(-11600 9400);
DISPLAY 1.021277 (-11600 9400);
DISPLAY INVISIBLE (-11600 9400);
FORCEPROP 2 LAST $XR0 16J8<> 
J 0
(-11669 9350);
DISPLAY 0.638298 (-11669 9350);
PAINT MONO (-11669 9350);
FORCEADD OFFPAGE_OUT..1
R 2
(-11450 9250);
FORCEPROP 1 LAST BODY_TYPE COMMENT
J 2
(-11460 9385);
DISPLAY 0.808511 (-11460 9385);
PAINT GREEN (-11460 9385);
DISPLAY INVISIBLE (-11460 9385);
FORCEPROP 1 LAST CDS_LMAN_SYM_OUTLINE -50,50,50,-50
J 2
(-11450 9250);
DISPLAY 0.468085 (-11450 9250);
PAINT GREEN (-11450 9250);
DISPLAY INVISIBLE (-11450 9250);
FORCEPROP 2 LAST CDS_LIB cls
J 0
(-11450 9250);
DISPLAY INVISIBLE (-11450 9250);
FORCEPROP 1 LAST OFFPAGE TRUE
J 2
(-11460 9305);
DISPLAY 0.808511 (-11460 9305);
PAINT GREEN (-11460 9305);
DISPLAY INVISIBLE (-11460 9305);
FORCEPROP 2 LAST PATH I176
J 0
(-11600 9300);
DISPLAY 1.021277 (-11600 9300);
DISPLAY INVISIBLE (-11600 9300);
FORCEPROP 2 LAST $XR0 16K8< 
J 0
(-11633 9250);
DISPLAY 0.638298 (-11633 9250);
PAINT MONO (-11633 9250);
FORCEADD OFFPAGE_BI..1
R 2
(-8150 4600);
FORCEPROP 2 LAST CDS_LIB cls
J 2
(-8150 4600);
DISPLAY INVISIBLE (-8150 4600);
FORCEPROP 2 LAST PATH I177
J 2
(-8200 4700);
DISPLAY 1.021277 (-8200 4700);
DISPLAY INVISIBLE (-8200 4700);
FORCEPROP 1 LAST OFFPAGE TRUE
J 2
(-8160 4655);
DISPLAY 0.808511 (-8160 4655);
PAINT GREEN (-8160 4655);
DISPLAY INVISIBLE (-8160 4655);
FORCEPROP 1 LAST BODY_TYPE COMMENT
J 2
(-8160 4735);
DISPLAY 0.808511 (-8160 4735);
PAINT GREEN (-8160 4735);
DISPLAY INVISIBLE (-8160 4735);
FORCEPROP 1 LAST CDS_LMAN_SYM_OUTLINE -50,50,50,-50
J 2
(-8150 4600);
DISPLAY 0.468085 (-8150 4600);
PAINT GREEN (-8150 4600);
DISPLAY INVISIBLE (-8150 4600);
FORCEPROP 2 LAST $XR0 16E4<> 
J 0
(-8369 4600);
DISPLAY 0.638298 (-8369 4600);
PAINT MONO (-8369 4600);
FORCEADD OFFPAGE_IN..1
(-8150 4500);
FORCEPROP 1 LAST CDS_LMAN_SYM_OUTLINE -50,50,50,-50
J 0
(-8150 4500);
DISPLAY 0.468085 (-8150 4500);
PAINT GREEN (-8150 4500);
DISPLAY INVISIBLE (-8150 4500);
FORCEPROP 2 LAST CDS_LIB cls
J 0
(-8150 4500);
DISPLAY INVISIBLE (-8150 4500);
FORCEPROP 2 LAST PATH I178
J 0
(-8100 4600);
DISPLAY 1.021277 (-8100 4600);
DISPLAY INVISIBLE (-8100 4600);
FORCEPROP 1 LAST OFFPAGE TRUE
J 0
(-8140 4555);
DISPLAY 0.808511 (-8140 4555);
PAINT GREEN (-8140 4555);
DISPLAY INVISIBLE (-8140 4555);
FORCEPROP 1 LAST BODY_TYPE COMMENT
J 0
(-8140 4635);
DISPLAY 0.808511 (-8140 4635);
PAINT GREEN (-8140 4635);
DISPLAY INVISIBLE (-8140 4635);
FORCEPROP 2 LAST $XR0 16E4> 
J 0
(-8333 4500);
DISPLAY 0.638298 (-8333 4500);
PAINT MONO (-8333 4500);
FORCEADD OFFPAGE_IN..1
(-3900 5400);
FORCEPROP 2 LAST CDS_LIB cls
J 0
(-3900 5400);
DISPLAY INVISIBLE (-3900 5400);
FORCEPROP 2 LAST PATH I179
J 0
(-3850 5500);
DISPLAY 1.021277 (-3850 5500);
DISPLAY INVISIBLE (-3850 5500);
FORCEPROP 1 LAST CDS_LMAN_SYM_OUTLINE -50,50,50,-50
J 0
(-3900 5400);
DISPLAY 0.468085 (-3900 5400);
PAINT GREEN (-3900 5400);
DISPLAY INVISIBLE (-3900 5400);
FORCEPROP 1 LAST BODY_TYPE COMMENT
J 0
(-3890 5535);
DISPLAY 0.808511 (-3890 5535);
PAINT GREEN (-3890 5535);
DISPLAY INVISIBLE (-3890 5535);
FORCEPROP 1 LAST OFFPAGE TRUE
J 0
(-3890 5455);
DISPLAY 0.808511 (-3890 5455);
PAINT GREEN (-3890 5455);
DISPLAY INVISIBLE (-3890 5455);
FORCEPROP 2 LAST $XR0 25D6<> 
J 0
(-4114 5400);
DISPLAY 0.638298 (-4114 5400);
PAINT MONO (-4114 5400);
FORCEADD OFFPAGE_IN..1
(-3900 5450);
FORCEPROP 1 LAST BODY_TYPE COMMENT
J 0
(-3890 5585);
DISPLAY 0.808511 (-3890 5585);
PAINT GREEN (-3890 5585);
DISPLAY INVISIBLE (-3890 5585);
FORCEPROP 1 LAST OFFPAGE TRUE
J 0
(-3890 5505);
DISPLAY 0.808511 (-3890 5505);
PAINT GREEN (-3890 5505);
DISPLAY INVISIBLE (-3890 5505);
FORCEPROP 1 LAST CDS_LMAN_SYM_OUTLINE -50,50,50,-50
J 0
(-3900 5450);
DISPLAY 0.468085 (-3900 5450);
PAINT GREEN (-3900 5450);
DISPLAY INVISIBLE (-3900 5450);
FORCEPROP 2 LAST PATH I180
J 0
(-3850 5550);
DISPLAY 1.021277 (-3850 5550);
DISPLAY INVISIBLE (-3850 5550);
FORCEPROP 2 LAST CDS_LIB cls
J 0
(-3900 5450);
DISPLAY INVISIBLE (-3900 5450);
FORCEPROP 2 LAST $XR0 25D6<> 
J 0
(-4114 5450);
DISPLAY 0.638298 (-4114 5450);
PAINT MONO (-4114 5450);
FORCEADD OFFPAGE_IN..1
(-7800 10700);
FORCEPROP 2 LAST CDS_LIB cls
J 0
(-7800 10700);
DISPLAY INVISIBLE (-7800 10700);
FORCEPROP 2 LAST PATH I181
J 0
(-7750 10800);
DISPLAY 1.021277 (-7750 10800);
DISPLAY INVISIBLE (-7750 10800);
FORCEPROP 1 LAST CDS_LMAN_SYM_OUTLINE -50,50,50,-50
J 0
(-7800 10700);
DISPLAY 0.468085 (-7800 10700);
PAINT GREEN (-7800 10700);
DISPLAY INVISIBLE (-7800 10700);
FORCEPROP 1 LAST BODY_TYPE COMMENT
J 0
(-7790 10835);
DISPLAY 0.808511 (-7790 10835);
PAINT GREEN (-7790 10835);
DISPLAY INVISIBLE (-7790 10835);
FORCEPROP 1 LAST OFFPAGE TRUE
J 0
(-7790 10755);
DISPLAY 0.808511 (-7790 10755);
PAINT GREEN (-7790 10755);
DISPLAY INVISIBLE (-7790 10755);
FORCEPROP 2 LAST $XR0 25D6<> 
J 0
(-8014 10700);
DISPLAY 0.638298 (-8014 10700);
PAINT MONO (-8014 10700);
FORCEADD OFFPAGE_OUT..1
(-3550 9800);
FORCEPROP 2 LAST PATH I25
J 0
(-3450 9850);
DISPLAY 1.021277 (-3450 9850);
DISPLAY INVISIBLE (-3450 9850);
FORCEPROP 1 LAST OFFPAGE TRUE
J 0
(-3540 9855);
DISPLAY 0.808511 (-3540 9855);
PAINT GREEN (-3540 9855);
DISPLAY INVISIBLE (-3540 9855);
FORCEPROP 1 LAST BODY_TYPE COMMENT
J 0
(-3540 9935);
DISPLAY 0.808511 (-3540 9935);
PAINT GREEN (-3540 9935);
DISPLAY INVISIBLE (-3540 9935);
FORCEPROP 1 LAST CDS_LMAN_SYM_OUTLINE -50,50,50,-50
J 0
(-3550 9800);
DISPLAY 0.468085 (-3550 9800);
PAINT GREEN (-3550 9800);
DISPLAY INVISIBLE (-3550 9800);
FORCEPROP 2 LAST CDS_LIB cls
J 0
(-3550 9800);
DISPLAY INVISIBLE (-3550 9800);
FORCEPROP 2 LAST $XR0 20F2< 
J 0
(-3495 9800);
DISPLAY 0.638298 (-3495 9800);
PAINT MONO (-3495 9800);
FORCEADD OFFPAGE_BI..1
(-3550 9900);
FORCEPROP 2 LAST PATH I26
J 0
(-3450 9950);
DISPLAY 1.021277 (-3450 9950);
DISPLAY INVISIBLE (-3450 9950);
FORCEPROP 1 LAST OFFPAGE TRUE
J 0
(-3540 9955);
DISPLAY 0.808511 (-3540 9955);
PAINT GREEN (-3540 9955);
DISPLAY INVISIBLE (-3540 9955);
FORCEPROP 1 LAST BODY_TYPE COMMENT
J 0
(-3540 10035);
DISPLAY 0.808511 (-3540 10035);
PAINT GREEN (-3540 10035);
DISPLAY INVISIBLE (-3540 10035);
FORCEPROP 1 LAST CDS_LMAN_SYM_OUTLINE -50,50,50,-50
J 0
(-3550 9900);
DISPLAY 0.468085 (-3550 9900);
PAINT GREEN (-3550 9900);
DISPLAY INVISIBLE (-3550 9900);
FORCEPROP 2 LAST CDS_LIB cls
J 0
(-3550 9900);
DISPLAY INVISIBLE (-3550 9900);
FORCEPROP 2 LAST $XR0 20F2<> 
J 0
(-3490 9900);
DISPLAY 0.638298 (-3490 9900);
PAINT MONO (-3490 9900);
FORCEADD OFFPAGE_OUT..1
(-3550 10100);
FORCEPROP 2 LAST PATH I27
J 0
(-3300 10150);
DISPLAY 1.021277 (-3300 10150);
DISPLAY INVISIBLE (-3300 10150);
FORCEPROP 1 LAST OFFPAGE TRUE
J 0
(-3540 10155);
DISPLAY 0.808511 (-3540 10155);
PAINT GREEN (-3540 10155);
DISPLAY INVISIBLE (-3540 10155);
FORCEPROP 2 LAST CDS_LIB cls
J 0
(-3550 10100);
DISPLAY INVISIBLE (-3550 10100);
FORCEPROP 1 LAST CDS_LMAN_SYM_OUTLINE -50,50,50,-50
J 0
(-3550 10100);
DISPLAY 0.468085 (-3550 10100);
PAINT GREEN (-3550 10100);
DISPLAY INVISIBLE (-3550 10100);
FORCEPROP 1 LAST BODY_TYPE COMMENT
J 0
(-3540 10235);
DISPLAY 0.808511 (-3540 10235);
PAINT GREEN (-3540 10235);
DISPLAY INVISIBLE (-3540 10235);
FORCEPROP 2 LAST $XR0 19G4<> 
J 0
(-3495 10100);
DISPLAY 0.638298 (-3495 10100);
PAINT MONO (-3495 10100);
FORCEADD OFFPAGE_BI..1
(-3550 10200);
FORCEPROP 2 LAST PATH I28
J 0
(-3300 10250);
DISPLAY 1.021277 (-3300 10250);
DISPLAY INVISIBLE (-3300 10250);
FORCEPROP 1 LAST OFFPAGE TRUE
J 0
(-3540 10255);
DISPLAY 0.808511 (-3540 10255);
PAINT GREEN (-3540 10255);
DISPLAY INVISIBLE (-3540 10255);
FORCEPROP 2 LAST CDS_LIB cls
J 0
(-3550 10200);
DISPLAY INVISIBLE (-3550 10200);
FORCEPROP 1 LAST CDS_LMAN_SYM_OUTLINE -50,50,50,-50
J 0
(-3550 10200);
DISPLAY 0.468085 (-3550 10200);
PAINT GREEN (-3550 10200);
DISPLAY INVISIBLE (-3550 10200);
FORCEPROP 1 LAST BODY_TYPE COMMENT
J 0
(-3540 10335);
DISPLAY 0.808511 (-3540 10335);
PAINT GREEN (-3540 10335);
DISPLAY INVISIBLE (-3540 10335);
FORCEPROP 2 LAST $XR0 19G4<> 
J 0
(-3490 10200);
DISPLAY 0.638298 (-3490 10200);
PAINT MONO (-3490 10200);
FORCEADD OFFPAGE_OUT..1
(-3550 10400);
FORCEPROP 2 LAST PATH I29
J 0
(-3450 10450);
DISPLAY 1.021277 (-3450 10450);
DISPLAY INVISIBLE (-3450 10450);
FORCEPROP 1 LAST OFFPAGE TRUE
J 0
(-3540 10455);
DISPLAY 0.808511 (-3540 10455);
PAINT GREEN (-3540 10455);
DISPLAY INVISIBLE (-3540 10455);
FORCEPROP 2 LAST CDS_LIB cls
J 0
(-3550 10400);
DISPLAY INVISIBLE (-3550 10400);
FORCEPROP 1 LAST CDS_LMAN_SYM_OUTLINE -50,50,50,-50
J 0
(-3550 10400);
DISPLAY 0.468085 (-3550 10400);
PAINT GREEN (-3550 10400);
DISPLAY INVISIBLE (-3550 10400);
FORCEPROP 1 LAST BODY_TYPE COMMENT
J 0
(-3540 10535);
DISPLAY 0.808511 (-3540 10535);
PAINT GREEN (-3540 10535);
DISPLAY INVISIBLE (-3540 10535);
FORCEPROP 2 LAST $XR0 18E4< 
J 0
(-3495 10400);
DISPLAY 0.638298 (-3495 10400);
PAINT MONO (-3495 10400);
FORCEADD OFFPAGE_BI..1
(-3550 10500);
FORCEPROP 2 LAST PATH I30
J 0
(-3450 10550);
DISPLAY 1.021277 (-3450 10550);
DISPLAY INVISIBLE (-3450 10550);
FORCEPROP 1 LAST OFFPAGE TRUE
J 0
(-3540 10555);
DISPLAY 0.808511 (-3540 10555);
PAINT GREEN (-3540 10555);
DISPLAY INVISIBLE (-3540 10555);
FORCEPROP 2 LAST CDS_LIB cls
J 0
(-3550 10500);
DISPLAY INVISIBLE (-3550 10500);
FORCEPROP 1 LAST CDS_LMAN_SYM_OUTLINE -50,50,50,-50
J 0
(-3550 10500);
DISPLAY 0.468085 (-3550 10500);
PAINT GREEN (-3550 10500);
DISPLAY INVISIBLE (-3550 10500);
FORCEPROP 1 LAST BODY_TYPE COMMENT
J 0
(-3540 10635);
DISPLAY 0.808511 (-3540 10635);
PAINT GREEN (-3540 10635);
DISPLAY INVISIBLE (-3540 10635);
FORCEPROP 2 LAST $XR0 18E4<> 
J 0
(-3490 10500);
DISPLAY 0.638298 (-3490 10500);
PAINT MONO (-3490 10500);
FORCEADD OFFPAGE_OUT..1
(-3550 10700);
FORCEPROP 2 LAST PATH I31
J 0
(-3450 10750);
DISPLAY 1.021277 (-3450 10750);
DISPLAY INVISIBLE (-3450 10750);
FORCEPROP 1 LAST OFFPAGE TRUE
J 0
(-3540 10755);
DISPLAY 0.808511 (-3540 10755);
PAINT GREEN (-3540 10755);
DISPLAY INVISIBLE (-3540 10755);
FORCEPROP 2 LAST CDS_LIB cls
J 0
(-3550 10700);
DISPLAY INVISIBLE (-3550 10700);
FORCEPROP 1 LAST CDS_LMAN_SYM_OUTLINE -50,50,50,-50
J 0
(-3550 10700);
DISPLAY 0.468085 (-3550 10700);
PAINT GREEN (-3550 10700);
DISPLAY INVISIBLE (-3550 10700);
FORCEPROP 1 LAST BODY_TYPE COMMENT
J 0
(-3540 10835);
DISPLAY 0.808511 (-3540 10835);
PAINT GREEN (-3540 10835);
DISPLAY INVISIBLE (-3540 10835);
FORCEPROP 2 LAST $XR0 17D3<> 
J 0
(-3495 10700);
DISPLAY 0.638298 (-3495 10700);
PAINT MONO (-3495 10700);
FORCEADD OFFPAGE_BI..1
(-3550 10800);
FORCEPROP 2 LAST PATH I32
J 0
(-3450 10850);
DISPLAY 1.021277 (-3450 10850);
DISPLAY INVISIBLE (-3450 10850);
FORCEPROP 1 LAST OFFPAGE TRUE
J 0
(-3540 10855);
DISPLAY 0.808511 (-3540 10855);
PAINT GREEN (-3540 10855);
DISPLAY INVISIBLE (-3540 10855);
FORCEPROP 2 LAST CDS_LIB cls
J 0
(-3550 10800);
DISPLAY INVISIBLE (-3550 10800);
FORCEPROP 1 LAST CDS_LMAN_SYM_OUTLINE -50,50,50,-50
J 0
(-3550 10800);
DISPLAY 0.468085 (-3550 10800);
PAINT GREEN (-3550 10800);
DISPLAY INVISIBLE (-3550 10800);
FORCEPROP 1 LAST BODY_TYPE COMMENT
J 0
(-3540 10935);
DISPLAY 0.808511 (-3540 10935);
PAINT GREEN (-3540 10935);
DISPLAY INVISIBLE (-3540 10935);
FORCEPROP 2 LAST $XR0 17D3<> 
J 0
(-3490 10800);
DISPLAY 0.638298 (-3490 10800);
PAINT MONO (-3490 10800);
FORCEADD PCA9546APW_TSSOP16..1
(-6550 10900);
FORCEPROP 1 LAST $LOCATION U4
J 0
(-6500 11000);
DISPLAY 1.212766 (-6500 11000);
PAINT GREEN (-6500 11000);
FORCEPROP 0 LAST CDS_LOCATION U4
J 0
(-6500 11200);
DISPLAY 1.021277 (-6500 11200);
DISPLAY INVISIBLE (-6500 11200);
FORCEPROP 0 LAST $SEC 1
J 0
(-6500 11200);
DISPLAY 0.680851 (-6500 11200);
PAINT MONO (-6500 11200);
DISPLAY INVISIBLE (-6500 11200);
FORCEPROP 0 LAST CDS_SEC 1
J 0
(-6500 11200);
DISPLAY 1.021277 (-6500 11200);
DISPLAY INVISIBLE (-6500 11200);
FORCEPROP 0 LASTPIN (-6650 10100) $PN 1
J 2
(-6660 10110);
DISPLAY 0.680851 (-6660 10110);
PAINT MONO (-6660 10110);
FORCEPROP 0 LASTPIN (-6650 10000) $PN 2
J 2
(-6660 10010);
DISPLAY 0.680851 (-6660 10010);
PAINT MONO (-6660 10010);
FORCEPROP 0 LASTPIN (-6650 9900) $PN 13
J 2
(-6660 9910);
DISPLAY 0.680851 (-6660 9910);
PAINT MONO (-6660 9910);
FORCEPROP 0 LASTPIN (-6650 10800) $PN 3
J 2
(-6660 10810);
DISPLAY 0.680851 (-6660 10810);
PAINT MONO (-6660 10810);
FORCEPROP 0 LASTPIN (-5750 10700) $PN 5
J 0
(-5740 10710);
DISPLAY 0.680851 (-5740 10710);
PAINT MONO (-5740 10710);
FORCEPROP 0 LASTPIN (-5750 10400) $PN 7
J 0
(-5740 10410);
DISPLAY 0.680851 (-5740 10410);
PAINT MONO (-5740 10410);
FORCEPROP 0 LASTPIN (-5750 10100) $PN 10
J 0
(-5740 10110);
DISPLAY 0.680851 (-5740 10110);
PAINT MONO (-5740 10110);
FORCEPROP 0 LASTPIN (-5750 9800) $PN 12
J 0
(-5740 9810);
DISPLAY 0.680851 (-5740 9810);
PAINT MONO (-5740 9810);
FORCEPROP 0 LASTPIN (-6650 10400) $PN 14
J 2
(-6660 10410);
DISPLAY 0.680851 (-6660 10410);
PAINT MONO (-6660 10410);
FORCEPROP 0 LASTPIN (-5750 10800) $PN 4
J 0
(-5740 10810);
DISPLAY 0.680851 (-5740 10810);
PAINT MONO (-5740 10810);
FORCEPROP 0 LASTPIN (-5750 10500) $PN 6
J 0
(-5740 10510);
DISPLAY 0.680851 (-5740 10510);
PAINT MONO (-5740 10510);
FORCEPROP 0 LASTPIN (-5750 10200) $PN 9
J 0
(-5740 10210);
DISPLAY 0.680851 (-5740 10210);
PAINT MONO (-5740 10210);
FORCEPROP 0 LASTPIN (-5750 9900) $PN 11
J 0
(-5740 9910);
DISPLAY 0.680851 (-5740 9910);
PAINT MONO (-5740 9910);
FORCEPROP 0 LASTPIN (-6650 10500) $PN 15
J 2
(-6660 10510);
DISPLAY 0.680851 (-6660 10510);
PAINT MONO (-6660 10510);
FORCEPROP 1 LAST PATH I33
J 0
(-6500 10950);
DISPLAY 1.212766 (-6500 10950);
PAINT GREEN (-6500 10950);
DISPLAY INVISIBLE (-6500 10950);
FORCEPROP 2 LASTPIN (-6650 9900) SIG_NAME UN$5$PCA9546APWTSSOP16$I33$A2
J 0
(-6640 9910);
DISPLAY 0.659574 (-6640 9910);
PAINT MONO (-6640 9910);
DISPLAY INVISIBLE (-6640 9910);
FORCEPROP 2 LASTPIN (-6650 10000) SIG_NAME UN$5$PCA9546APWTSSOP16$I33$A1
J 0
(-6640 10010);
DISPLAY 0.659574 (-6640 10010);
PAINT MONO (-6640 10010);
DISPLAY INVISIBLE (-6640 10010);
FORCEPROP 2 LASTPIN (-6650 10100) SIG_NAME UN$5$PCA9546APWTSSOP16$I33$A0
J 0
(-6640 10110);
DISPLAY 0.659574 (-6640 10110);
PAINT MONO (-6640 10110);
DISPLAY INVISIBLE (-6640 10110);
FORCEPROP 2 LAST CDS_LIB interface
J 0
(-6550 10900);
DISPLAY INVISIBLE (-6550 10900);
FORCEPROP 1 LAST CDS_LMAN_SYM_OUTLINE 0,0,700,-1200
J 0
(-6550 10900);
DISPLAY 0.468085 (-6550 10900);
PAINT GREEN (-6550 10900);
DISPLAY INVISIBLE (-6550 10900);
FORCEPROP 1 LAST CLS_PN G223-10280-01
J 0
(-6500 11100);
DISPLAY 1.212766 (-6500 11100);
PAINT GREEN (-6500 11100);
FORCEPROP 0 LAST PART_NUMBER TCA9546APWR
J 0
(-6500 11250);
DISPLAY 1.021277 (-6500 11250);
FORCEADD RESISTOR..1
(-9550 9250);
FORCEPROP 1 LAST $LOCATION R59
J 2
(-9750 9250);
DISPLAY 1.212766 (-9750 9250);
PAINT GREEN (-9750 9250);
FORCEPROP 0 LAST CDS_LOCATION R59
J 0
(-9350 9350);
DISPLAY 1.021277 (-9350 9350);
DISPLAY INVISIBLE (-9350 9350);
FORCEPROP 0 LAST $SEC 1
J 0
(-9350 9350);
DISPLAY 0.680851 (-9350 9350);
PAINT MONO (-9350 9350);
DISPLAY INVISIBLE (-9350 9350);
FORCEPROP 0 LAST CDS_SEC 1
J 0
(-9350 9350);
DISPLAY 1.021277 (-9350 9350);
DISPLAY INVISIBLE (-9350 9350);
FORCEPROP 0 LASTPIN (-9650 9250) $PN 1
J 2
(-9660 9260);
DISPLAY 0.680851 (-9660 9260);
PAINT MONO (-9660 9260);
FORCEPROP 0 LASTPIN (-9400 9250) $PN 2
J 0
(-9390 9260);
DISPLAY 0.680851 (-9390 9260);
PAINT MONO (-9390 9260);
FORCEPROP 2 LAST SIGNAL_MODEL DEFAULT_RESISTOR_33OHM_2_1
J 0
(-9700 9450);
DISPLAY 1.021277 (-9700 9450);
DISPLAY INVISIBLE (-9700 9450);
FORCEPROP 1 LAST CDS_LMAN_SYM_OUTLINE -50,50,100,-50
J 0
(-9550 9250);
DISPLAY 0.468085 (-9550 9250);
PAINT GREEN (-9550 9250);
DISPLAY INVISIBLE (-9550 9250);
FORCEPROP 2 LAST CDS_LIB passive
J 0
(-9550 9250);
DISPLAY INVISIBLE (-9550 9250);
FORCEPROP 1 LAST CLS_PN G155-133R0-01
J 0
(-9686 9450);
DISPLAY 1.212766 (-9686 9450);
PAINT GREEN (-9686 9450);
DISPLAY INVISIBLE (-9686 9450);
FORCEPROP 1 LAST TOLERANCE 1%
J 0
(-9747 9505);
DISPLAY 1.212766 (-9747 9505);
PAINT GREEN (-9747 9505);
DISPLAY INVISIBLE (-9747 9505);
FORCEPROP 1 LAST PATH I4
J 0
(-9747 9355);
DISPLAY 1.212766 (-9747 9355);
PAINT GREEN (-9747 9355);
DISPLAY INVISIBLE (-9747 9355);
FORCEPROP 0 LAST PACKAGE 0402
J 0
(-9600 9200);
DISPLAY 0.808511 (-9600 9200);
FORCEPROP 1 LAST VALUE 33OHM
J 0
(-9350 9250);
DISPLAY 1.234043 (-9350 9250);
PAINT GREEN (-9350 9250);
FORCEADD CAPACITOR..2
(-5850 8900);
FORCEPROP 1 LAST $LOCATION C38
J 0
(-5800 8750);
DISPLAY 1.212766 (-5800 8750);
PAINT GREEN (-5800 8750);
FORCEPROP 0 LAST CDS_LOCATION C38
J 0
(-5800 9050);
DISPLAY 1.021277 (-5800 9050);
DISPLAY INVISIBLE (-5800 9050);
FORCEPROP 0 LAST $SEC 1
J 0
(-5800 9050);
DISPLAY 0.680851 (-5800 9050);
PAINT MONO (-5800 9050);
DISPLAY INVISIBLE (-5800 9050);
FORCEPROP 0 LAST CDS_SEC 1
J 0
(-5800 9050);
DISPLAY 1.021277 (-5800 9050);
DISPLAY INVISIBLE (-5800 9050);
FORCEPROP 0 LASTPIN (-5850 9000) $PN 1
R 1
J 0
(-5860 9010);
DISPLAY 0.680851 (-5860 9010);
PAINT MONO (-5860 9010);
FORCEPROP 0 LASTPIN (-5850 8750) $PN 2
R 1
J 2
(-5860 8740);
DISPLAY 0.680851 (-5860 8740);
PAINT MONO (-5860 8740);
FORCEPROP 1 LAST TOLERANCE 10%
J 0
(-6000 9000);
DISPLAY 1.212766 (-6000 9000);
PAINT GREEN (-6000 9000);
DISPLAY INVISIBLE (-6000 9000);
FORCEPROP 2 LAST CDS_LIB passive
J 0
(-5850 8900);
DISPLAY INVISIBLE (-5850 8900);
FORCEPROP 1 LAST CDS_LMAN_SYM_OUTLINE -50,0,50,-50
J 0
(-5850 8900);
DISPLAY 0.468085 (-5850 8900);
PAINT GREEN (-5850 8900);
DISPLAY INVISIBLE (-5850 8900);
FORCEPROP 1 LAST CLS_PN G105-0B104-CK
J 0
(-5950 8950);
DISPLAY 1.212766 (-5950 8950);
PAINT GREEN (-5950 8950);
DISPLAY INVISIBLE (-5950 8950);
FORCEPROP 1 LAST PATH I45
J 0
(-5950 8950);
DISPLAY 1.212766 (-5950 8950);
PAINT GREEN (-5950 8950);
DISPLAY INVISIBLE (-5950 8950);
FORCEPROP 0 LAST VOLTAGE 10V
J 0
(-5750 8850);
DISPLAY 1.021277 (-5750 8850);
FORCEPROP 1 LAST VALUE 0.1UF
J 0
(-5800 8950);
DISPLAY 1.212766 (-5800 8950);
PAINT GREEN (-5800 8950);
FORCEPROP 0 LAST PACKAGE 0402
J 0
(-5800 9100);
DISPLAY 1.021277 (-5800 9100);
FORCEADD OFFPAGE_BI..1
R 2
(-11450 10500);
FORCEPROP 1 LAST BODY_TYPE COMMENT
J 2
(-11460 10635);
DISPLAY 0.808511 (-11460 10635);
PAINT GREEN (-11460 10635);
DISPLAY INVISIBLE (-11460 10635);
FORCEPROP 1 LAST CDS_LMAN_SYM_OUTLINE -50,50,50,-50
J 2
(-11450 10500);
DISPLAY 0.468085 (-11450 10500);
PAINT GREEN (-11450 10500);
DISPLAY INVISIBLE (-11450 10500);
FORCEPROP 2 LAST CDS_LIB cls
J 0
(-11450 10500);
DISPLAY INVISIBLE (-11450 10500);
FORCEPROP 1 LAST OFFPAGE TRUE
J 2
(-11460 10555);
DISPLAY 0.808511 (-11460 10555);
PAINT GREEN (-11460 10555);
DISPLAY INVISIBLE (-11460 10555);
FORCEPROP 2 LAST PATH I5
J 0
(-11600 10550);
DISPLAY 1.021277 (-11600 10550);
DISPLAY INVISIBLE (-11600 10550);
FORCEPROP 2 LAST $XR0 24H16<> 
J 0
(-11700 10500);
DISPLAY 0.638298 (-11700 10500);
PAINT MONO (-11700 10500);
FORCEADD RESISTOR..1
(-5150 9350);
FORCEPROP 1 LAST $LOCATION R61
J 2
(-5300 9350);
DISPLAY 1.212766 (-5300 9350);
PAINT GREEN (-5300 9350);
FORCEPROP 0 LAST CDS_LOCATION R61
J 0
(-5250 9500);
DISPLAY 1.021277 (-5250 9500);
DISPLAY INVISIBLE (-5250 9500);
FORCEPROP 0 LAST $SEC 1
J 0
(-5250 9500);
DISPLAY 0.680851 (-5250 9500);
PAINT MONO (-5250 9500);
DISPLAY INVISIBLE (-5250 9500);
FORCEPROP 0 LAST CDS_SEC 1
J 0
(-5250 9500);
DISPLAY 1.021277 (-5250 9500);
DISPLAY INVISIBLE (-5250 9500);
FORCEPROP 0 LASTPIN (-5250 9350) $PN 1
J 2
(-5260 9360);
DISPLAY 0.680851 (-5260 9360);
PAINT MONO (-5260 9360);
FORCEPROP 0 LASTPIN (-5000 9350) $PN 2
J 0
(-4990 9360);
DISPLAY 0.680851 (-4990 9360);
PAINT MONO (-4990 9360);
FORCEPROP 1 LAST TOLERANCE -
J 0
(-5347 9605);
DISPLAY 1.212766 (-5347 9605);
PAINT GREEN (-5347 9605);
DISPLAY INVISIBLE (-5347 9605);
FORCEPROP 1 LAST CLS_PN G155-100R0-J0
J 0
(-5286 9550);
DISPLAY 1.212766 (-5286 9550);
PAINT GREEN (-5286 9550);
DISPLAY INVISIBLE (-5286 9550);
FORCEPROP 1 LAST PATH I52
J 0
(-5347 9455);
DISPLAY 1.212766 (-5347 9455);
PAINT GREEN (-5347 9455);
DISPLAY INVISIBLE (-5347 9455);
FORCEPROP 2 LAST CDS_LIB passive
J 0
(-5150 9350);
DISPLAY INVISIBLE (-5150 9350);
FORCEPROP 1 LAST CDS_LMAN_SYM_OUTLINE -50,50,100,-50
J 0
(-5150 9350);
DISPLAY 0.468085 (-5150 9350);
PAINT GREEN (-5150 9350);
DISPLAY INVISIBLE (-5150 9350);
FORCEPROP 1 LAST VALUE 0OHM
J 0
(-4850 9350);
DISPLAY 1.212766 (-4850 9350);
PAINT GREEN (-4850 9350);
FORCEPROP 0 LAST PACKAGE 0402
J 0
(-5200 9400);
DISPLAY 0.808511 (-5200 9400);
FORCEPROP 0 LAST NO_ASSY TRUE
J 0
(-5350 9450);
DISPLAY 0.808511 (-5350 9450);
DISPLAY BOTH (-5350 9450);
FORCEADD GND_SG..1
(-6300 8300);
FORCEPROP 3 LASTPIN (-6250 8350) SIG_NAME SG\g
J 0
(-6240 8360);
DISPLAY 0.659574 (-6240 8360);
PAINT MONO (-6240 8360);
DISPLAY INVISIBLE (-6240 8360);
FORCEPROP 2 LAST CDS_LIB cls
J 0
(-6300 8300);
DISPLAY INVISIBLE (-6300 8300);
FORCEPROP 1 LAST CDS_LMAN_SYM_OUTLINE 0,0,100,-50
J 0
(-6300 8300);
DISPLAY 0.468085 (-6300 8300);
PAINT GREEN (-6300 8300);
DISPLAY INVISIBLE (-6300 8300);
FORCEPROP 1 LAST BODY_TYPE PLUMBING
J 0
(-6285 8285);
DISPLAY 0.808511 (-6285 8285);
PAINT GREEN (-6285 8285);
DISPLAY INVISIBLE (-6285 8285);
FORCEPROP 1 LAST PATH I53
J 0
(-6265 8300);
DISPLAY 0.808511 (-6265 8300);
PAINT GREEN (-6265 8300);
DISPLAY INVISIBLE (-6265 8300);
FORCEPROP 1 LAST HDL_POWER SG
J 1
(-6245 8205);
DISPLAY 0.808511 (-6245 8205);
PAINT GREEN (-6245 8205);
FORCEPROP 0 LAST VOLTAGE 0
J 0
(-6200 8300);
DISPLAY 1.021277 (-6200 8300);
FORCEADD PCA9546APW_TSSOP16..2
(-6450 9150);
FORCEPROP 1 LAST $LOCATION U4
J 2
(-6500 8650);
DISPLAY 1.212766 (-6500 8650);
PAINT GREEN (-6500 8650);
FORCEPROP 0 LAST CDS_LOCATION U4
J 0
(-6500 8900);
DISPLAY 1.021277 (-6500 8900);
DISPLAY INVISIBLE (-6500 8900);
FORCEPROP 0 LAST $SEC 2
J 0
(-6500 8900);
DISPLAY 0.680851 (-6500 8900);
PAINT MONO (-6500 8900);
DISPLAY INVISIBLE (-6500 8900);
FORCEPROP 0 LAST CDS_SEC 2
J 0
(-6500 8900);
DISPLAY 1.021277 (-6500 8900);
DISPLAY INVISIBLE (-6500 8900);
FORCEPROP 0 LASTPIN (-6250 9250) $PN 16
R 1
J 0
(-6260 9260);
DISPLAY 0.680851 (-6260 9260);
PAINT MONO (-6260 9260);
FORCEPROP 0 LASTPIN (-6250 8550) $PN 8
R 1
J 2
(-6260 8540);
DISPLAY 0.680851 (-6260 8540);
PAINT MONO (-6260 8540);
FORCEPROP 2 LAST CDS_LIB interface
J 0
(-6450 9150);
DISPLAY INVISIBLE (-6450 9150);
FORCEPROP 1 LAST CDS_LMAN_SYM_OUTLINE 0,0,400,-500
J 0
(-6450 9150);
DISPLAY 0.468085 (-6450 9150);
PAINT GREEN (-6450 9150);
DISPLAY INVISIBLE (-6450 9150);
FORCEPROP 1 LAST PATH I54
J 2
(-6500 9200);
DISPLAY 1.212766 (-6500 9200);
PAINT GREEN (-6500 9200);
DISPLAY INVISIBLE (-6500 9200);
FORCEPROP 1 LAST CLS_PN G223-10280-01
J 2
(-6450 8550);
DISPLAY 1.212766 (-6450 8550);
PAINT GREEN (-6450 8550);
FORCEADD RESISTOR..2
R 1
(-5150 9200);
FORCEPROP 1 LAST $LOCATION R62
J 0
(-5450 9200);
DISPLAY 1.212766 (-5450 9200);
PAINT GREEN (-5450 9200);
FORCEPROP 0 LAST CDS_LOCATION R62
R 1
J 0
(-4900 9300);
DISPLAY 1.021277 (-4900 9300);
DISPLAY INVISIBLE (-4900 9300);
FORCEPROP 0 LAST $SEC 1
R 1
J 0
(-4900 9300);
DISPLAY 0.680851 (-4900 9300);
PAINT MONO (-4900 9300);
DISPLAY INVISIBLE (-4900 9300);
FORCEPROP 0 LAST CDS_SEC 1
R 1
J 0
(-4900 9300);
DISPLAY 1.021277 (-4900 9300);
DISPLAY INVISIBLE (-4900 9300);
FORCEPROP 0 LASTPIN (-5250 9200) $PN 1
J 2
(-5260 9210);
DISPLAY 0.680851 (-5260 9210);
PAINT MONO (-5260 9210);
FORCEPROP 0 LASTPIN (-5000 9200) $PN 2
J 0
(-4990 9210);
DISPLAY 0.680851 (-4990 9210);
PAINT MONO (-4990 9210);
FORCEPROP 1 LAST PATH I55
R 1
J 0
(-5255 9003);
DISPLAY 1.212766 (-5255 9003);
PAINT GREEN (-5255 9003);
DISPLAY INVISIBLE (-5255 9003);
FORCEPROP 1 LAST TOLERANCE -
R 1
J 0
(-5405 9003);
DISPLAY 1.212766 (-5405 9003);
PAINT GREEN (-5405 9003);
DISPLAY INVISIBLE (-5405 9003);
FORCEPROP 1 LAST CLS_PN G155-100R0-J0
R 1
J 0
(-5350 9064);
DISPLAY 1.212766 (-5350 9064);
PAINT GREEN (-5350 9064);
DISPLAY INVISIBLE (-5350 9064);
FORCEPROP 1 LAST CDS_LMAN_SYM_OUTLINE -50,50,50,-100
R 1
J 0
(-5150 9200);
DISPLAY 0.468085 (-5150 9200);
PAINT GREEN (-5150 9200);
DISPLAY INVISIBLE (-5150 9200);
FORCEPROP 2 LAST CDS_LIB passive
J 0
(-5150 9200);
DISPLAY INVISIBLE (-5150 9200);
FORCEPROP 1 LAST VALUE 0OHM
J 0
(-4850 9200);
DISPLAY 1.212766 (-4850 9200);
PAINT GREEN (-4850 9200);
FORCEPROP 0 LAST PACKAGE 0402
J 0
(-5200 9100);
DISPLAY 0.808511 (-5200 9100);
FORCEADD OFFPAGE_IN..1
(-11450 10400);
FORCEPROP 1 LAST BODY_TYPE COMMENT
J 0
(-11440 10535);
DISPLAY 0.808511 (-11440 10535);
PAINT GREEN (-11440 10535);
DISPLAY INVISIBLE (-11440 10535);
FORCEPROP 2 LAST CDS_LIB cls
J 0
(-11450 10400);
DISPLAY INVISIBLE (-11450 10400);
FORCEPROP 1 LAST CDS_LMAN_SYM_OUTLINE -50,50,50,-50
J 0
(-11450 10400);
DISPLAY 0.468085 (-11450 10400);
PAINT GREEN (-11450 10400);
DISPLAY INVISIBLE (-11450 10400);
FORCEPROP 1 LAST OFFPAGE TRUE
J 0
(-11440 10455);
DISPLAY 0.808511 (-11440 10455);
PAINT GREEN (-11440 10455);
DISPLAY INVISIBLE (-11440 10455);
FORCEPROP 2 LAST PATH I6
J 0
(-11600 10450);
DISPLAY 1.021277 (-11600 10450);
DISPLAY INVISIBLE (-11600 10450);
FORCEPROP 2 LAST $XR0 24J16> 
J 0
(-11664 10400);
DISPLAY 0.638298 (-11664 10400);
PAINT MONO (-11664 10400);
FORCEADD RESISTOR..2
R 1
(-8100 11150);
FORCEPROP 1 LAST $LOCATION R146
J 0
(-8450 11150);
DISPLAY 1.212766 (-8450 11150);
PAINT GREEN (-8450 11150);
FORCEPROP 0 LAST CDS_LOCATION R146
R 1
J 0
(-7850 11250);
DISPLAY 1.021277 (-7850 11250);
DISPLAY INVISIBLE (-7850 11250);
FORCEPROP 0 LAST $SEC 1
R 1
J 0
(-7850 11250);
DISPLAY 0.680851 (-7850 11250);
PAINT MONO (-7850 11250);
DISPLAY INVISIBLE (-7850 11250);
FORCEPROP 0 LAST CDS_SEC 1
R 1
J 0
(-7850 11250);
DISPLAY 1.021277 (-7850 11250);
DISPLAY INVISIBLE (-7850 11250);
FORCEPROP 0 LASTPIN (-8200 11150) $PN 1
J 2
(-8210 11160);
DISPLAY 0.680851 (-8210 11160);
PAINT MONO (-8210 11160);
FORCEPROP 0 LASTPIN (-7950 11150) $PN 2
J 0
(-7940 11160);
DISPLAY 0.680851 (-7940 11160);
PAINT MONO (-7940 11160);
FORCEPROP 1 LAST CDS_LMAN_SYM_OUTLINE -50,50,50,-100
R 1
J 0
(-8100 11150);
DISPLAY 0.468085 (-8100 11150);
PAINT GREEN (-8100 11150);
DISPLAY INVISIBLE (-8100 11150);
FORCEPROP 2 LAST CDS_LIB passive
J 0
(-8100 11150);
DISPLAY INVISIBLE (-8100 11150);
FORCEPROP 1 LAST TOLERANCE 1%
R 1
J 0
(-8355 10953);
DISPLAY 1.212766 (-8355 10953);
PAINT GREEN (-8355 10953);
DISPLAY INVISIBLE (-8355 10953);
FORCEPROP 1 LAST PATH I60
R 1
J 0
(-8205 10953);
DISPLAY 1.212766 (-8205 10953);
PAINT GREEN (-8205 10953);
DISPLAY INVISIBLE (-8205 10953);
FORCEPROP 1 LAST CLS_PN G155-11002-01
R 1
J 0
(-8300 11014);
DISPLAY 1.212766 (-8300 11014);
PAINT GREEN (-8300 11014);
DISPLAY INVISIBLE (-8300 11014);
FORCEPROP 0 LAST PACKAGE 0402
J 0
(-8150 11200);
DISPLAY 0.808511 (-8150 11200);
FORCEPROP 1 LAST VALUE 10KOHM
J 0
(-7850 11150);
DISPLAY 1.212766 (-7850 11150);
PAINT GREEN (-7850 11150);
FORCEADD RESISTOR..2
R 1
(-8100 9350);
FORCEPROP 1 LAST $LOCATION R155
J 0
(-8500 9350);
DISPLAY 1.212766 (-8500 9350);
PAINT GREEN (-8500 9350);
FORCEPROP 0 LAST CDS_LOCATION R155
R 1
J 0
(-7850 9450);
DISPLAY 1.021277 (-7850 9450);
DISPLAY INVISIBLE (-7850 9450);
FORCEPROP 0 LAST $SEC 1
R 1
J 0
(-7850 9450);
DISPLAY 0.680851 (-7850 9450);
PAINT MONO (-7850 9450);
DISPLAY INVISIBLE (-7850 9450);
FORCEPROP 0 LAST CDS_SEC 1
R 1
J 0
(-7850 9450);
DISPLAY 1.021277 (-7850 9450);
DISPLAY INVISIBLE (-7850 9450);
FORCEPROP 0 LASTPIN (-8200 9350) $PN 1
J 2
(-8210 9360);
DISPLAY 0.680851 (-8210 9360);
PAINT MONO (-8210 9360);
FORCEPROP 0 LASTPIN (-7950 9350) $PN 2
J 0
(-7940 9360);
DISPLAY 0.680851 (-7940 9360);
PAINT MONO (-7940 9360);
FORCEPROP 1 LAST CLS_PN G155-14701-01
R 1
J 0
(-8300 9214);
DISPLAY 1.212766 (-8300 9214);
PAINT GREEN (-8300 9214);
DISPLAY INVISIBLE (-8300 9214);
FORCEPROP 1 LAST CDS_LMAN_SYM_OUTLINE -50,50,50,-100
R 1
J 0
(-8100 9350);
DISPLAY 0.468085 (-8100 9350);
PAINT GREEN (-8100 9350);
DISPLAY INVISIBLE (-8100 9350);
FORCEPROP 2 LAST CDS_LIB passive
J 0
(-8100 9350);
DISPLAY INVISIBLE (-8100 9350);
FORCEPROP 1 LAST TOLERANCE 1%
R 1
J 0
(-8355 9153);
DISPLAY 1.212766 (-8355 9153);
PAINT GREEN (-8355 9153);
DISPLAY INVISIBLE (-8355 9153);
FORCEPROP 1 LAST PATH I66
R 1
J 0
(-8205 9153);
DISPLAY 1.212766 (-8205 9153);
PAINT GREEN (-8205 9153);
DISPLAY INVISIBLE (-8205 9153);
FORCEPROP 1 LAST VALUE 4.7KOHM
J 0
(-7850 9350);
DISPLAY 1.212766 (-7850 9350);
PAINT GREEN (-7850 9350);
FORCEPROP 0 LAST NO_ASSY TRUE
J 0
(-8300 9300);
DISPLAY 1.021277 (-8300 9300);
DISPLAY BOTH (-8300 9300);
FORCEPROP 0 LAST PACKAGE 0402
J 0
(-8150 9400);
DISPLAY 0.808511 (-8150 9400);
FORCEADD RESISTOR..1
(-9750 10400);
FORCEPROP 1 LAST $LOCATION R145
J 2
(-9900 10400);
DISPLAY 1.212766 (-9900 10400);
PAINT GREEN (-9900 10400);
FORCEPROP 0 LAST CDS_LOCATION R145
J 0
(-9550 10500);
DISPLAY 1.021277 (-9550 10500);
DISPLAY INVISIBLE (-9550 10500);
FORCEPROP 0 LAST $SEC 1
J 0
(-9550 10500);
DISPLAY 0.680851 (-9550 10500);
PAINT MONO (-9550 10500);
DISPLAY INVISIBLE (-9550 10500);
FORCEPROP 0 LAST CDS_SEC 1
J 0
(-9550 10500);
DISPLAY 1.021277 (-9550 10500);
DISPLAY INVISIBLE (-9550 10500);
FORCEPROP 0 LASTPIN (-9850 10400) $PN 1
J 2
(-9860 10410);
DISPLAY 0.680851 (-9860 10410);
PAINT MONO (-9860 10410);
FORCEPROP 0 LASTPIN (-9600 10400) $PN 2
J 0
(-9590 10410);
DISPLAY 0.680851 (-9590 10410);
PAINT MONO (-9590 10410);
FORCEPROP 2 LAST SIGNAL_MODEL DEFAULT_RESISTOR_33OHM_2_1
J 0
(-9900 10600);
DISPLAY 1.021277 (-9900 10600);
DISPLAY INVISIBLE (-9900 10600);
FORCEPROP 1 LAST CDS_LMAN_SYM_OUTLINE -50,50,100,-50
J 0
(-9750 10400);
DISPLAY 0.468085 (-9750 10400);
PAINT GREEN (-9750 10400);
DISPLAY INVISIBLE (-9750 10400);
FORCEPROP 2 LAST CDS_LIB passive
J 0
(-9750 10400);
DISPLAY INVISIBLE (-9750 10400);
FORCEPROP 1 LAST CLS_PN G155-133R0-01
J 0
(-9886 10600);
DISPLAY 1.212766 (-9886 10600);
PAINT GREEN (-9886 10600);
DISPLAY INVISIBLE (-9886 10600);
FORCEPROP 1 LAST TOLERANCE 1%
J 0
(-9947 10655);
DISPLAY 1.212766 (-9947 10655);
PAINT GREEN (-9947 10655);
DISPLAY INVISIBLE (-9947 10655);
FORCEPROP 1 LAST PATH I67
J 0
(-9947 10505);
DISPLAY 1.212766 (-9947 10505);
PAINT GREEN (-9947 10505);
DISPLAY INVISIBLE (-9947 10505);
FORCEPROP 0 LAST PACKAGE 0402
J 0
(-9200 10400);
DISPLAY 0.808511 (-9200 10400);
FORCEPROP 1 LAST VALUE 33OHM
J 0
(-9550 10400);
DISPLAY 1.234043 (-9550 10400);
PAINT GREEN (-9550 10400);
FORCEADD RESISTOR..1
(-9750 10500);
FORCEPROP 1 LAST $LOCATION R144
J 2
(-9900 10500);
DISPLAY 1.212766 (-9900 10500);
PAINT GREEN (-9900 10500);
FORCEPROP 0 LAST CDS_LOCATION R144
J 0
(-9550 10600);
DISPLAY 1.021277 (-9550 10600);
DISPLAY INVISIBLE (-9550 10600);
FORCEPROP 0 LAST $SEC 1
J 0
(-9550 10600);
DISPLAY 0.680851 (-9550 10600);
PAINT MONO (-9550 10600);
DISPLAY INVISIBLE (-9550 10600);
FORCEPROP 0 LAST CDS_SEC 1
J 0
(-9550 10600);
DISPLAY 1.021277 (-9550 10600);
DISPLAY INVISIBLE (-9550 10600);
FORCEPROP 0 LASTPIN (-9850 10500) $PN 1
J 2
(-9860 10510);
DISPLAY 0.680851 (-9860 10510);
PAINT MONO (-9860 10510);
FORCEPROP 0 LASTPIN (-9600 10500) $PN 2
J 0
(-9590 10510);
DISPLAY 0.680851 (-9590 10510);
PAINT MONO (-9590 10510);
FORCEPROP 2 LAST SIGNAL_MODEL DEFAULT_RESISTOR_33OHM_2_1
J 0
(-9900 10700);
DISPLAY 1.021277 (-9900 10700);
DISPLAY INVISIBLE (-9900 10700);
FORCEPROP 2 LAST CDS_LIB passive
J 0
(-9750 10500);
DISPLAY INVISIBLE (-9750 10500);
FORCEPROP 1 LAST CDS_LMAN_SYM_OUTLINE -50,50,100,-50
J 0
(-9750 10500);
DISPLAY 0.468085 (-9750 10500);
PAINT GREEN (-9750 10500);
DISPLAY INVISIBLE (-9750 10500);
FORCEPROP 1 LAST CLS_PN G155-133R0-01
J 0
(-9886 10700);
DISPLAY 1.212766 (-9886 10700);
PAINT GREEN (-9886 10700);
DISPLAY INVISIBLE (-9886 10700);
FORCEPROP 1 LAST TOLERANCE 1%
J 0
(-9947 10755);
DISPLAY 1.212766 (-9947 10755);
PAINT GREEN (-9947 10755);
DISPLAY INVISIBLE (-9947 10755);
FORCEPROP 1 LAST PATH I68
J 0
(-9947 10605);
DISPLAY 1.212766 (-9947 10605);
PAINT GREEN (-9947 10605);
DISPLAY INVISIBLE (-9947 10605);
FORCEPROP 0 LAST PACKAGE 0402
J 0
(-9200 10500);
DISPLAY 0.808511 (-9200 10500);
FORCEPROP 1 LAST VALUE 33OHM
J 0
(-9550 10500);
DISPLAY 1.234043 (-9550 10500);
PAINT GREEN (-9550 10500);
FORCEADD RESISTOR..1
(-9750 10200);
FORCEPROP 1 LAST $LOCATION R26
J 2
(-9950 10200);
DISPLAY 1.212766 (-9950 10200);
PAINT GREEN (-9950 10200);
FORCEPROP 0 LAST CDS_LOCATION R26
J 0
(-9500 10300);
DISPLAY 1.021277 (-9500 10300);
DISPLAY INVISIBLE (-9500 10300);
FORCEPROP 0 LAST $SEC 1
J 0
(-9500 10300);
DISPLAY 0.680851 (-9500 10300);
PAINT MONO (-9500 10300);
DISPLAY INVISIBLE (-9500 10300);
FORCEPROP 0 LAST CDS_SEC 1
J 0
(-9500 10300);
DISPLAY 1.021277 (-9500 10300);
DISPLAY INVISIBLE (-9500 10300);
FORCEPROP 0 LASTPIN (-9850 10200) $PN 1
J 2
(-9860 10210);
DISPLAY 0.680851 (-9860 10210);
PAINT MONO (-9860 10210);
FORCEPROP 0 LASTPIN (-9600 10200) $PN 2
J 0
(-9590 10210);
DISPLAY 0.680851 (-9590 10210);
PAINT MONO (-9590 10210);
FORCEPROP 2 LAST CDS_LIB passive
J 0
(-9750 10200);
DISPLAY INVISIBLE (-9750 10200);
FORCEPROP 1 LAST CDS_LMAN_SYM_OUTLINE -50,50,100,-50
J 0
(-9750 10200);
DISPLAY 0.468085 (-9750 10200);
PAINT GREEN (-9750 10200);
DISPLAY INVISIBLE (-9750 10200);
FORCEPROP 1 LAST CLS_PN G155-133R0-01
J 0
(-9886 10400);
DISPLAY 1.212766 (-9886 10400);
PAINT GREEN (-9886 10400);
DISPLAY INVISIBLE (-9886 10400);
FORCEPROP 1 LAST TOLERANCE 1%
J 0
(-9947 10455);
DISPLAY 1.212766 (-9947 10455);
PAINT GREEN (-9947 10455);
DISPLAY INVISIBLE (-9947 10455);
FORCEPROP 1 LAST PATH I69
J 0
(-9947 10305);
DISPLAY 1.212766 (-9947 10305);
PAINT GREEN (-9947 10305);
DISPLAY INVISIBLE (-9947 10305);
FORCEPROP 0 LAST NO_ASSY TRUE
J 0
(-9850 10250);
DISPLAY 0.638298 (-9850 10250);
DISPLAY BOTH (-9850 10250);
FORCEPROP 1 LAST VALUE 33OHM
J 0
(-9500 10200);
DISPLAY 1.212766 (-9500 10200);
PAINT GREEN (-9500 10200);
FORCEPROP 0 LAST PACKAGE 0402
J 0
(-9200 10200);
DISPLAY 0.808511 (-9200 10200);
FORCEADD RESISTOR..1
(-9750 10100);
FORCEPROP 1 LAST $LOCATION R27
J 2
(-9950 10100);
DISPLAY 1.212766 (-9950 10100);
PAINT GREEN (-9950 10100);
FORCEPROP 0 LAST CDS_LOCATION R27
J 0
(-9500 10200);
DISPLAY 1.021277 (-9500 10200);
DISPLAY INVISIBLE (-9500 10200);
FORCEPROP 0 LAST $SEC 1
J 0
(-9500 10200);
DISPLAY 0.680851 (-9500 10200);
PAINT MONO (-9500 10200);
DISPLAY INVISIBLE (-9500 10200);
FORCEPROP 0 LAST CDS_SEC 1
J 0
(-9500 10200);
DISPLAY 1.021277 (-9500 10200);
DISPLAY INVISIBLE (-9500 10200);
FORCEPROP 0 LASTPIN (-9850 10100) $PN 1
J 2
(-9860 10110);
DISPLAY 0.680851 (-9860 10110);
PAINT MONO (-9860 10110);
FORCEPROP 0 LASTPIN (-9600 10100) $PN 2
J 0
(-9590 10110);
DISPLAY 0.680851 (-9590 10110);
PAINT MONO (-9590 10110);
FORCEPROP 2 LAST CDS_LIB passive
J 0
(-9750 10100);
DISPLAY INVISIBLE (-9750 10100);
FORCEPROP 1 LAST CDS_LMAN_SYM_OUTLINE -50,50,100,-50
J 0
(-9750 10100);
DISPLAY 0.468085 (-9750 10100);
PAINT GREEN (-9750 10100);
DISPLAY INVISIBLE (-9750 10100);
FORCEPROP 1 LAST CLS_PN G155-133R0-01
J 0
(-9886 10300);
DISPLAY 1.212766 (-9886 10300);
PAINT GREEN (-9886 10300);
DISPLAY INVISIBLE (-9886 10300);
FORCEPROP 1 LAST TOLERANCE 1%
J 0
(-9947 10355);
DISPLAY 1.212766 (-9947 10355);
PAINT GREEN (-9947 10355);
DISPLAY INVISIBLE (-9947 10355);
FORCEPROP 1 LAST PATH I72
J 0
(-9947 10205);
DISPLAY 1.212766 (-9947 10205);
PAINT GREEN (-9947 10205);
DISPLAY INVISIBLE (-9947 10205);
FORCEPROP 0 LAST NO_ASSY TRUE
J 0
(-9850 10050);
DISPLAY 0.638298 (-9850 10050);
DISPLAY BOTH (-9850 10050);
FORCEPROP 1 LAST VALUE 33OHM
J 0
(-9511 10105);
DISPLAY 1.212766 (-9511 10105);
PAINT GREEN (-9511 10105);
FORCEPROP 0 LAST PACKAGE 0402
J 0
(-9200 10100);
DISPLAY 0.808511 (-9200 10100);
FORCEADD OFFPAGE_IN..1
(-11450 10100);
FORCEPROP 1 LAST BODY_TYPE COMMENT
J 0
(-11440 10235);
DISPLAY 0.808511 (-11440 10235);
PAINT GREEN (-11440 10235);
DISPLAY INVISIBLE (-11440 10235);
FORCEPROP 1 LAST CDS_LMAN_SYM_OUTLINE -50,50,50,-50
J 0
(-11450 10100);
DISPLAY 0.468085 (-11450 10100);
PAINT GREEN (-11450 10100);
DISPLAY INVISIBLE (-11450 10100);
FORCEPROP 2 LAST CDS_LIB cls
J 0
(-11450 10100);
DISPLAY INVISIBLE (-11450 10100);
FORCEPROP 1 LAST OFFPAGE TRUE
J 0
(-11440 10155);
DISPLAY 0.808511 (-11440 10155);
PAINT GREEN (-11440 10155);
DISPLAY INVISIBLE (-11440 10155);
FORCEPROP 2 LAST PATH I73
J 0
(-11400 10200);
DISPLAY 1.021277 (-11400 10200);
DISPLAY INVISIBLE (-11400 10200);
FORCEPROP 2 LAST $XR1 16H3< 
J 0
(-11782 10100);
DISPLAY 0.638298 (-11782 10100);
PAINT MONO (-11782 10100);
FORCEPROP 2 LAST $XR0 9K9> 
J 0
(-11602 10100);
DISPLAY 0.638298 (-11602 10100);
PAINT MONO (-11602 10100);
FORCEADD OFFPAGE_BI..1
R 2
(-11450 10200);
FORCEPROP 1 LAST BODY_TYPE COMMENT
J 2
(-11460 10335);
DISPLAY 0.808511 (-11460 10335);
PAINT GREEN (-11460 10335);
DISPLAY INVISIBLE (-11460 10335);
FORCEPROP 1 LAST CDS_LMAN_SYM_OUTLINE -50,50,50,-50
J 2
(-11450 10200);
DISPLAY 0.468085 (-11450 10200);
PAINT GREEN (-11450 10200);
DISPLAY INVISIBLE (-11450 10200);
FORCEPROP 2 LAST CDS_LIB cls
J 0
(-11450 10200);
DISPLAY INVISIBLE (-11450 10200);
FORCEPROP 1 LAST OFFPAGE TRUE
J 2
(-11460 10255);
DISPLAY 0.808511 (-11460 10255);
PAINT GREEN (-11460 10255);
DISPLAY INVISIBLE (-11460 10255);
FORCEPROP 2 LAST PATH I74
J 0
(-11400 10300);
DISPLAY 1.021277 (-11400 10300);
DISPLAY INVISIBLE (-11400 10300);
FORCEPROP 2 LAST $XR1 16H3<> 
J 0
(-11848 10200);
DISPLAY 0.638298 (-11848 10200);
PAINT MONO (-11848 10200);
FORCEPROP 2 LAST $XR0 9K9<> 
J 0
(-11638 10200);
DISPLAY 0.638298 (-11638 10200);
PAINT MONO (-11638 10200);
FORCEADD VCC..1
(-3800 9450);
FORCEPROP 3 LASTPIN (-3750 9400) SIG_NAME XP3R3V_FPGA\g
J 0
(-3740 9410);
DISPLAY 0.659574 (-3740 9410);
PAINT MONO (-3740 9410);
DISPLAY INVISIBLE (-3740 9410);
FORCEPROP 1 LAST CDS_LMAN_SYM_OUTLINE -250,250,250,-250
J 0
(-3800 9450);
DISPLAY 0.468085 (-3800 9450);
PAINT GREEN (-3800 9450);
DISPLAY INVISIBLE (-3800 9450);
FORCEPROP 2 LAST CDS_LIB cls
J 0
(-3800 9450);
DISPLAY INVISIBLE (-3800 9450);
FORCEPROP 1 LAST BODY_TYPE PLUMBING
J 0
(-3845 9407);
DISPLAY 0.340426 (-3845 9407);
PAINT GREEN (-3845 9407);
DISPLAY INVISIBLE (-3845 9407);
FORCEPROP 1 LAST PATH I76
J 0
(-3765 9540);
DISPLAY 0.808511 (-3765 9540);
PAINT GREEN (-3765 9540);
DISPLAY INVISIBLE (-3765 9540);
FORCEPROP 1 LAST HDL_POWER XP3R3V_FPGA
J 1
(-3745 9505);
DISPLAY 1.021277 (-3745 9505);
PAINT GREEN (-3745 9505);
FORCEPROP 0 LAST VOLTAGE 3.3V
J 0
(-4000 9600);
DISPLAY 1.021277 (-4000 9600);
DISPLAY BOTH (-4000 9600);
FORCEADD VCC..1
(-8700 11300);
FORCEPROP 3 LASTPIN (-8650 11250) SIG_NAME XP3R3V_FPGA\g
J 0
(-8640 11260);
DISPLAY 0.659574 (-8640 11260);
PAINT MONO (-8640 11260);
DISPLAY INVISIBLE (-8640 11260);
FORCEPROP 1 LAST PATH I77
J 0
(-8665 11390);
DISPLAY 0.808511 (-8665 11390);
PAINT GREEN (-8665 11390);
DISPLAY INVISIBLE (-8665 11390);
FORCEPROP 1 LAST BODY_TYPE PLUMBING
J 0
(-8745 11257);
DISPLAY 0.340426 (-8745 11257);
PAINT GREEN (-8745 11257);
DISPLAY INVISIBLE (-8745 11257);
FORCEPROP 2 LAST CDS_LIB cls
J 0
(-8700 11300);
DISPLAY INVISIBLE (-8700 11300);
FORCEPROP 1 LAST CDS_LMAN_SYM_OUTLINE -250,250,250,-250
J 0
(-8700 11300);
DISPLAY 0.468085 (-8700 11300);
PAINT GREEN (-8700 11300);
DISPLAY INVISIBLE (-8700 11300);
FORCEPROP 1 LAST HDL_POWER XP3R3V_FPGA
J 1
(-8645 11355);
DISPLAY 1.021277 (-8645 11355);
PAINT GREEN (-8645 11355);
FORCEPROP 0 LAST VOLTAGE 3.3V
J 0
(-8950 11450);
DISPLAY 1.021277 (-8950 11450);
DISPLAY BOTH (-8950 11450);
FORCEADD VCC..1
(-4450 9450);
FORCEPROP 3 LASTPIN (-4400 9400) SIG_NAME XP2R5V_FPGA\g
J 0
(-4390 9410);
DISPLAY 0.659574 (-4390 9410);
PAINT MONO (-4390 9410);
DISPLAY INVISIBLE (-4390 9410);
FORCEPROP 1 LAST PATH I78
J 0
(-4415 9540);
DISPLAY 0.808511 (-4415 9540);
PAINT GREEN (-4415 9540);
DISPLAY INVISIBLE (-4415 9540);
FORCEPROP 1 LAST BODY_TYPE PLUMBING
J 0
(-4495 9407);
DISPLAY 0.340426 (-4495 9407);
PAINT GREEN (-4495 9407);
DISPLAY INVISIBLE (-4495 9407);
FORCEPROP 1 LAST CDS_LMAN_SYM_OUTLINE -250,250,250,-250
J 0
(-4450 9450);
DISPLAY 0.468085 (-4450 9450);
PAINT GREEN (-4450 9450);
DISPLAY INVISIBLE (-4450 9450);
FORCEPROP 2 LAST CDS_LIB cls
J 0
(-4450 9450);
DISPLAY INVISIBLE (-4450 9450);
FORCEPROP 1 LAST HDL_POWER XP2R5V_FPGA
J 1
(-4395 9505);
DISPLAY 1.021277 (-4395 9505);
PAINT GREEN (-4395 9505);
FORCEPROP 0 LAST VOLTAGE 2.5V
J 0
(-4650 9600);
DISPLAY 1.021277 (-4650 9600);
DISPLAY BOTH (-4650 9600);
FORCEADD RESISTOR..2
R 1
(-8100 11050);
FORCEPROP 1 LAST LOCATION R147
J 0
(-8450 11050);
DISPLAY 1.212766 (-8450 11050);
PAINT GREEN (-8450 11050);
FORCEPROP 0 LAST $SEC 1
R 1
J 0
(-7850 11150);
DISPLAY 0.680851 (-7850 11150);
PAINT MONO (-7850 11150);
DISPLAY INVISIBLE (-7850 11150);
FORCEPROP 0 LAST CDS_SEC 1
R 1
J 0
(-7850 11150);
DISPLAY 1.021277 (-7850 11150);
DISPLAY INVISIBLE (-7850 11150);
FORCEPROP 0 LASTPIN (-8200 11050) $PN 1
J 2
(-8210 11060);
DISPLAY 0.680851 (-8210 11060);
PAINT MONO (-8210 11060);
FORCEPROP 0 LASTPIN (-7950 11050) $PN 2
J 0
(-7940 11060);
DISPLAY 0.680851 (-7940 11060);
PAINT MONO (-7940 11060);
FORCEPROP 1 LAST PATH I80
R 1
J 0
(-8205 10853);
DISPLAY 1.212766 (-8205 10853);
PAINT GREEN (-8205 10853);
DISPLAY INVISIBLE (-8205 10853);
FORCEPROP 1 LAST TOLERANCE 1%
R 1
J 0
(-8355 10853);
DISPLAY 1.212766 (-8355 10853);
PAINT GREEN (-8355 10853);
DISPLAY INVISIBLE (-8355 10853);
FORCEPROP 2 LAST CDS_LIB passive
J 0
(-8100 11050);
DISPLAY INVISIBLE (-8100 11050);
FORCEPROP 1 LAST CDS_LMAN_SYM_OUTLINE -50,50,50,-100
R 1
J 0
(-8100 11050);
DISPLAY 0.468085 (-8100 11050);
PAINT GREEN (-8100 11050);
DISPLAY INVISIBLE (-8100 11050);
FORCEPROP 1 LAST CLS_PN G155-11002-01
R 1
J 0
(-8300 10914);
DISPLAY 1.212766 (-8300 10914);
PAINT GREEN (-8300 10914);
DISPLAY INVISIBLE (-8300 10914);
FORCEPROP 1 LAST VALUE 10KOHM
J 0
(-7850 11050);
DISPLAY 1.212766 (-7850 11050);
PAINT GREEN (-7850 11050);
FORCEPROP 0 LAST PACKAGE 0402
J 0
(-8150 11100);
DISPLAY 0.808511 (-8150 11100);
FORCEADD RESISTOR..2
R 1
(-8100 10950);
FORCEPROP 1 LAST LOCATION R148
J 0
(-8450 10950);
DISPLAY 1.212766 (-8450 10950);
PAINT GREEN (-8450 10950);
FORCEPROP 0 LAST $SEC 1
R 1
J 0
(-7850 11050);
DISPLAY 0.680851 (-7850 11050);
PAINT MONO (-7850 11050);
DISPLAY INVISIBLE (-7850 11050);
FORCEPROP 0 LAST CDS_SEC 1
R 1
J 0
(-7850 11050);
DISPLAY 1.021277 (-7850 11050);
DISPLAY INVISIBLE (-7850 11050);
FORCEPROP 0 LASTPIN (-8200 10950) $PN 1
J 2
(-8210 10960);
DISPLAY 0.680851 (-8210 10960);
PAINT MONO (-8210 10960);
FORCEPROP 0 LASTPIN (-7950 10950) $PN 2
J 0
(-7940 10960);
DISPLAY 0.680851 (-7940 10960);
PAINT MONO (-7940 10960);
FORCEPROP 1 LAST PATH I81
R 1
J 0
(-8205 10753);
DISPLAY 1.212766 (-8205 10753);
PAINT GREEN (-8205 10753);
DISPLAY INVISIBLE (-8205 10753);
FORCEPROP 1 LAST TOLERANCE 1%
R 1
J 0
(-8355 10753);
DISPLAY 1.212766 (-8355 10753);
PAINT GREEN (-8355 10753);
DISPLAY INVISIBLE (-8355 10753);
FORCEPROP 1 LAST CDS_LMAN_SYM_OUTLINE -50,50,50,-100
R 1
J 0
(-8100 10950);
DISPLAY 0.468085 (-8100 10950);
PAINT GREEN (-8100 10950);
DISPLAY INVISIBLE (-8100 10950);
FORCEPROP 2 LAST CDS_LIB passive
J 0
(-8100 10950);
DISPLAY INVISIBLE (-8100 10950);
FORCEPROP 1 LAST CLS_PN G155-11002-01
R 1
J 0
(-8300 10814);
DISPLAY 1.212766 (-8300 10814);
PAINT GREEN (-8300 10814);
DISPLAY INVISIBLE (-8300 10814);
FORCEPROP 1 LAST VALUE 10KOHM
J 0
(-7850 10950);
DISPLAY 1.212766 (-7850 10950);
PAINT GREEN (-7850 10950);
FORCEPROP 0 LAST PACKAGE 0402
J 0
(-8150 11000);
DISPLAY 0.808511 (-8150 11000);
FORCEADD RESISTOR..2
R 1
(-8100 10100);
FORCEPROP 1 LAST LOCATION R149
J 0
(-8450 10100);
DISPLAY 1.212766 (-8450 10100);
PAINT GREEN (-8450 10100);
FORCEPROP 0 LAST $SEC 1
R 1
J 0
(-7850 10200);
DISPLAY 0.680851 (-7850 10200);
PAINT MONO (-7850 10200);
DISPLAY INVISIBLE (-7850 10200);
FORCEPROP 0 LAST CDS_SEC 1
R 1
J 0
(-7850 10200);
DISPLAY 1.021277 (-7850 10200);
DISPLAY INVISIBLE (-7850 10200);
FORCEPROP 0 LASTPIN (-8200 10100) $PN 1
J 2
(-8210 10110);
DISPLAY 0.680851 (-8210 10110);
PAINT MONO (-8210 10110);
FORCEPROP 0 LASTPIN (-7950 10100) $PN 2
J 0
(-7940 10110);
DISPLAY 0.680851 (-7940 10110);
PAINT MONO (-7940 10110);
FORCEPROP 2 LAST CDS_LIB passive
J 0
(-8100 10100);
DISPLAY INVISIBLE (-8100 10100);
FORCEPROP 1 LAST CDS_LMAN_SYM_OUTLINE -50,50,50,-100
R 1
J 0
(-8100 10100);
DISPLAY 0.468085 (-8100 10100);
PAINT GREEN (-8100 10100);
DISPLAY INVISIBLE (-8100 10100);
FORCEPROP 1 LAST CLS_PN G155-14701-01
R 1
J 0
(-8300 9964);
DISPLAY 1.212766 (-8300 9964);
PAINT GREEN (-8300 9964);
DISPLAY INVISIBLE (-8300 9964);
FORCEPROP 1 LAST TOLERANCE 1%
R 1
J 0
(-8355 9903);
DISPLAY 1.212766 (-8355 9903);
PAINT GREEN (-8355 9903);
DISPLAY INVISIBLE (-8355 9903);
FORCEPROP 1 LAST PATH I82
R 1
J 0
(-8205 9903);
DISPLAY 1.212766 (-8205 9903);
PAINT GREEN (-8205 9903);
DISPLAY INVISIBLE (-8205 9903);
FORCEPROP 0 LAST NO_ASSY TRUE
J 0
(-8150 10150);
DISPLAY 1.021277 (-8150 10150);
DISPLAY BOTH (-8150 10150);
FORCEPROP 1 LAST VALUE 4.7KOHM
J 0
(-7850 10100);
DISPLAY 1.212766 (-7850 10100);
PAINT GREEN (-7850 10100);
FORCEPROP 0 LAST PACKAGE 0402
J 0
(-7400 10100);
DISPLAY 0.808511 (-7400 10100);
FORCEADD RESISTOR..2
R 1
(-8100 10000);
FORCEPROP 1 LAST LOCATION R150
J 0
(-8450 10000);
DISPLAY 1.212766 (-8450 10000);
PAINT GREEN (-8450 10000);
FORCEPROP 0 LAST $SEC 1
R 1
J 0
(-7850 10100);
DISPLAY 0.680851 (-7850 10100);
PAINT MONO (-7850 10100);
DISPLAY INVISIBLE (-7850 10100);
FORCEPROP 0 LAST CDS_SEC 1
R 1
J 0
(-7850 10100);
DISPLAY 1.021277 (-7850 10100);
DISPLAY INVISIBLE (-7850 10100);
FORCEPROP 0 LASTPIN (-8200 10000) $PN 1
J 2
(-8210 10010);
DISPLAY 0.680851 (-8210 10010);
PAINT MONO (-8210 10010);
FORCEPROP 0 LASTPIN (-7950 10000) $PN 2
J 0
(-7940 10010);
DISPLAY 0.680851 (-7940 10010);
PAINT MONO (-7940 10010);
FORCEPROP 2 LAST CDS_LIB passive
J 0
(-8100 10000);
DISPLAY INVISIBLE (-8100 10000);
FORCEPROP 1 LAST CDS_LMAN_SYM_OUTLINE -50,50,50,-100
R 1
J 0
(-8100 10000);
DISPLAY 0.468085 (-8100 10000);
PAINT GREEN (-8100 10000);
DISPLAY INVISIBLE (-8100 10000);
FORCEPROP 1 LAST CLS_PN G155-14701-01
R 1
J 0
(-8300 9864);
DISPLAY 1.212766 (-8300 9864);
PAINT GREEN (-8300 9864);
DISPLAY INVISIBLE (-8300 9864);
FORCEPROP 1 LAST TOLERANCE 1%
R 1
J 0
(-8355 9803);
DISPLAY 1.212766 (-8355 9803);
PAINT GREEN (-8355 9803);
DISPLAY INVISIBLE (-8355 9803);
FORCEPROP 1 LAST PATH I83
R 1
J 0
(-8205 9803);
DISPLAY 1.212766 (-8205 9803);
PAINT GREEN (-8205 9803);
DISPLAY INVISIBLE (-8205 9803);
FORCEPROP 0 LAST NO_ASSY TRUE
J 0
(-8150 10050);
DISPLAY 1.021277 (-8150 10050);
DISPLAY BOTH (-8150 10050);
FORCEPROP 1 LAST VALUE 4.7KOHM
J 0
(-7850 10000);
DISPLAY 1.212766 (-7850 10000);
PAINT GREEN (-7850 10000);
FORCEPROP 0 LAST PACKAGE 0402
J 0
(-7400 10000);
DISPLAY 0.808511 (-7400 10000);
FORCEADD RESISTOR..2
R 1
(-8100 9900);
FORCEPROP 1 LAST LOCATION R151
J 0
(-8450 9900);
DISPLAY 1.212766 (-8450 9900);
PAINT GREEN (-8450 9900);
FORCEPROP 0 LAST $SEC 1
R 1
J 0
(-7850 10000);
DISPLAY 0.680851 (-7850 10000);
PAINT MONO (-7850 10000);
DISPLAY INVISIBLE (-7850 10000);
FORCEPROP 0 LAST CDS_SEC 1
R 1
J 0
(-7850 10000);
DISPLAY 1.021277 (-7850 10000);
DISPLAY INVISIBLE (-7850 10000);
FORCEPROP 0 LASTPIN (-8200 9900) $PN 1
J 2
(-8210 9910);
DISPLAY 0.680851 (-8210 9910);
PAINT MONO (-8210 9910);
FORCEPROP 0 LASTPIN (-7950 9900) $PN 2
J 0
(-7940 9910);
DISPLAY 0.680851 (-7940 9910);
PAINT MONO (-7940 9910);
FORCEPROP 2 LAST CDS_LIB passive
J 0
(-8100 9900);
DISPLAY INVISIBLE (-8100 9900);
FORCEPROP 1 LAST CDS_LMAN_SYM_OUTLINE -50,50,50,-100
R 1
J 0
(-8100 9900);
DISPLAY 0.468085 (-8100 9900);
PAINT GREEN (-8100 9900);
DISPLAY INVISIBLE (-8100 9900);
FORCEPROP 1 LAST CLS_PN G155-14701-01
R 1
J 0
(-8300 9764);
DISPLAY 1.212766 (-8300 9764);
PAINT GREEN (-8300 9764);
DISPLAY INVISIBLE (-8300 9764);
FORCEPROP 1 LAST TOLERANCE 1%
R 1
J 0
(-8355 9703);
DISPLAY 1.212766 (-8355 9703);
PAINT GREEN (-8355 9703);
DISPLAY INVISIBLE (-8355 9703);
FORCEPROP 1 LAST PATH I84
R 1
J 0
(-8205 9703);
DISPLAY 1.212766 (-8205 9703);
PAINT GREEN (-8205 9703);
DISPLAY INVISIBLE (-8205 9703);
FORCEPROP 0 LAST NO_ASSY TRUE
J 0
(-8150 9950);
DISPLAY 1.021277 (-8150 9950);
DISPLAY BOTH (-8150 9950);
FORCEPROP 1 LAST VALUE 4.7KOHM
J 0
(-7850 9900);
DISPLAY 1.212766 (-7850 9900);
PAINT GREEN (-7850 9900);
FORCEPROP 0 LAST PACKAGE 0402
J 0
(-7400 9900);
DISPLAY 0.808511 (-7400 9900);
FORCEADD RESISTOR..2
R 1
(-8100 9700);
FORCEPROP 1 LAST LOCATION R152
J 0
(-8450 9700);
DISPLAY 1.212766 (-8450 9700);
PAINT GREEN (-8450 9700);
FORCEPROP 0 LAST $SEC 1
R 1
J 0
(-7850 9800);
DISPLAY 0.680851 (-7850 9800);
PAINT MONO (-7850 9800);
DISPLAY INVISIBLE (-7850 9800);
FORCEPROP 0 LAST CDS_SEC 1
R 1
J 0
(-7850 9800);
DISPLAY 1.021277 (-7850 9800);
DISPLAY INVISIBLE (-7850 9800);
FORCEPROP 0 LASTPIN (-8200 9700) $PN 1
J 2
(-8210 9710);
DISPLAY 0.680851 (-8210 9710);
PAINT MONO (-8210 9710);
FORCEPROP 0 LASTPIN (-7950 9700) $PN 2
J 0
(-7940 9710);
DISPLAY 0.680851 (-7940 9710);
PAINT MONO (-7940 9710);
FORCEPROP 2 LAST CDS_LIB passive
J 0
(-8100 9700);
DISPLAY INVISIBLE (-8100 9700);
FORCEPROP 1 LAST CDS_LMAN_SYM_OUTLINE -50,50,50,-100
R 1
J 0
(-8100 9700);
DISPLAY 0.468085 (-8100 9700);
PAINT GREEN (-8100 9700);
DISPLAY INVISIBLE (-8100 9700);
FORCEPROP 1 LAST CLS_PN G155-14701-01
R 1
J 0
(-8300 9564);
DISPLAY 1.212766 (-8300 9564);
PAINT GREEN (-8300 9564);
DISPLAY INVISIBLE (-8300 9564);
FORCEPROP 1 LAST TOLERANCE 1%
R 1
J 0
(-8355 9503);
DISPLAY 1.212766 (-8355 9503);
PAINT GREEN (-8355 9503);
DISPLAY INVISIBLE (-8355 9503);
FORCEPROP 1 LAST PATH I85
R 1
J 0
(-8205 9503);
DISPLAY 1.212766 (-8205 9503);
PAINT GREEN (-8205 9503);
DISPLAY INVISIBLE (-8205 9503);
FORCEPROP 0 LAST PACKAGE 0402
J 0
(-8150 9750);
DISPLAY 0.808511 (-8150 9750);
FORCEPROP 1 LAST VALUE 4.7KOHM
J 0
(-7850 9700);
DISPLAY 1.212766 (-7850 9700);
PAINT GREEN (-7850 9700);
FORCEADD RESISTOR..2
R 1
(-8100 9600);
FORCEPROP 1 LAST LOCATION R153
J 0
(-8450 9600);
DISPLAY 1.212766 (-8450 9600);
PAINT GREEN (-8450 9600);
FORCEPROP 0 LAST $SEC 1
R 1
J 0
(-7850 9700);
DISPLAY 0.680851 (-7850 9700);
PAINT MONO (-7850 9700);
DISPLAY INVISIBLE (-7850 9700);
FORCEPROP 0 LAST CDS_SEC 1
R 1
J 0
(-7850 9700);
DISPLAY 1.021277 (-7850 9700);
DISPLAY INVISIBLE (-7850 9700);
FORCEPROP 0 LASTPIN (-8200 9600) $PN 1
J 2
(-8210 9610);
DISPLAY 0.680851 (-8210 9610);
PAINT MONO (-8210 9610);
FORCEPROP 0 LASTPIN (-7950 9600) $PN 2
J 0
(-7940 9610);
DISPLAY 0.680851 (-7940 9610);
PAINT MONO (-7940 9610);
FORCEPROP 2 LAST CDS_LIB passive
J 0
(-8100 9600);
DISPLAY INVISIBLE (-8100 9600);
FORCEPROP 1 LAST CDS_LMAN_SYM_OUTLINE -50,50,50,-100
R 1
J 0
(-8100 9600);
DISPLAY 0.468085 (-8100 9600);
PAINT GREEN (-8100 9600);
DISPLAY INVISIBLE (-8100 9600);
FORCEPROP 1 LAST CLS_PN G155-14701-01
R 1
J 0
(-8300 9464);
DISPLAY 1.212766 (-8300 9464);
PAINT GREEN (-8300 9464);
DISPLAY INVISIBLE (-8300 9464);
FORCEPROP 1 LAST TOLERANCE 1%
R 1
J 0
(-8355 9403);
DISPLAY 1.212766 (-8355 9403);
PAINT GREEN (-8355 9403);
DISPLAY INVISIBLE (-8355 9403);
FORCEPROP 1 LAST PATH I86
R 1
J 0
(-8205 9403);
DISPLAY 1.212766 (-8205 9403);
PAINT GREEN (-8205 9403);
DISPLAY INVISIBLE (-8205 9403);
FORCEPROP 1 LAST VALUE 4.7KOHM
J 0
(-7850 9600);
DISPLAY 1.212766 (-7850 9600);
PAINT GREEN (-7850 9600);
FORCEPROP 0 LAST PACKAGE 0402
J 0
(-8150 9650);
DISPLAY 0.808511 (-8150 9650);
FORCEADD RESISTOR..2
R 1
(-8100 9500);
FORCEPROP 1 LAST LOCATION R154
J 0
(-8450 9500);
DISPLAY 1.212766 (-8450 9500);
PAINT GREEN (-8450 9500);
FORCEPROP 0 LAST $SEC 1
R 1
J 0
(-7850 9600);
DISPLAY 0.680851 (-7850 9600);
PAINT MONO (-7850 9600);
DISPLAY INVISIBLE (-7850 9600);
FORCEPROP 0 LAST CDS_SEC 1
R 1
J 0
(-7850 9600);
DISPLAY 1.021277 (-7850 9600);
DISPLAY INVISIBLE (-7850 9600);
FORCEPROP 0 LASTPIN (-8200 9500) $PN 1
J 2
(-8210 9510);
DISPLAY 0.680851 (-8210 9510);
PAINT MONO (-8210 9510);
FORCEPROP 0 LASTPIN (-7950 9500) $PN 2
J 0
(-7940 9510);
DISPLAY 0.680851 (-7940 9510);
PAINT MONO (-7940 9510);
FORCEPROP 1 LAST CLS_PN G155-14701-01
R 1
J 0
(-8300 9364);
DISPLAY 1.212766 (-8300 9364);
PAINT GREEN (-8300 9364);
DISPLAY INVISIBLE (-8300 9364);
FORCEPROP 1 LAST CDS_LMAN_SYM_OUTLINE -50,50,50,-100
R 1
J 0
(-8100 9500);
DISPLAY 0.468085 (-8100 9500);
PAINT GREEN (-8100 9500);
DISPLAY INVISIBLE (-8100 9500);
FORCEPROP 2 LAST CDS_LIB passive
J 0
(-8100 9500);
DISPLAY INVISIBLE (-8100 9500);
FORCEPROP 1 LAST TOLERANCE 1%
R 1
J 0
(-8355 9303);
DISPLAY 1.212766 (-8355 9303);
PAINT GREEN (-8355 9303);
DISPLAY INVISIBLE (-8355 9303);
FORCEPROP 1 LAST PATH I87
R 1
J 0
(-8205 9303);
DISPLAY 1.212766 (-8205 9303);
PAINT GREEN (-8205 9303);
DISPLAY INVISIBLE (-8205 9303);
FORCEPROP 0 LAST PACKAGE 0402
J 0
(-8150 9550);
DISPLAY 0.808511 (-8150 9550);
FORCEPROP 1 LAST VALUE 4.7KOHM
J 0
(-7850 9500);
DISPLAY 1.212766 (-7850 9500);
PAINT GREEN (-7850 9500);
FORCEADD RESISTOR..1
(-9550 9350);
FORCEPROP 1 LAST LOCATION R58
J 2
(-9750 9350);
DISPLAY 1.212766 (-9750 9350);
PAINT GREEN (-9750 9350);
FORCEPROP 0 LAST $SEC 1
J 0
(-9350 9450);
DISPLAY 0.680851 (-9350 9450);
PAINT MONO (-9350 9450);
DISPLAY INVISIBLE (-9350 9450);
FORCEPROP 0 LAST CDS_SEC 1
J 0
(-9350 9450);
DISPLAY 1.021277 (-9350 9450);
DISPLAY INVISIBLE (-9350 9450);
FORCEPROP 0 LASTPIN (-9650 9350) $PN 1
J 2
(-9660 9360);
DISPLAY 0.680851 (-9660 9360);
PAINT MONO (-9660 9360);
FORCEPROP 0 LASTPIN (-9400 9350) $PN 2
J 0
(-9390 9360);
DISPLAY 0.680851 (-9390 9360);
PAINT MONO (-9390 9360);
FORCEPROP 2 LAST CDS_LIB passive
J 0
(-9550 9350);
DISPLAY INVISIBLE (-9550 9350);
FORCEPROP 1 LAST CDS_LMAN_SYM_OUTLINE -50,50,100,-50
J 0
(-9550 9350);
DISPLAY 0.468085 (-9550 9350);
PAINT GREEN (-9550 9350);
DISPLAY INVISIBLE (-9550 9350);
FORCEPROP 2 LAST SIGNAL_MODEL DEFAULT_RESISTOR_33OHM_2_1
J 0
(-9700 9550);
DISPLAY 1.021277 (-9700 9550);
DISPLAY INVISIBLE (-9700 9550);
FORCEPROP 1 LAST CLS_PN G155-133R0-01
J 0
(-9686 9550);
DISPLAY 1.212766 (-9686 9550);
PAINT GREEN (-9686 9550);
DISPLAY INVISIBLE (-9686 9550);
FORCEPROP 1 LAST TOLERANCE 1%
J 0
(-9747 9605);
DISPLAY 1.212766 (-9747 9605);
PAINT GREEN (-9747 9605);
DISPLAY INVISIBLE (-9747 9605);
FORCEPROP 1 LAST PATH I88
J 0
(-9747 9455);
DISPLAY 1.212766 (-9747 9455);
PAINT GREEN (-9747 9455);
DISPLAY INVISIBLE (-9747 9455);
FORCEPROP 0 LAST PACKAGE 0402
J 0
(-9600 9350);
DISPLAY 0.808511 (-9600 9350);
FORCEPROP 1 LAST VALUE 33OHM
J 0
(-9350 9350);
DISPLAY 1.234043 (-9350 9350);
PAINT GREEN (-9350 9350);
FORCEADD AT24MAC402_SOT23_5..1
(-5950 6050);
FORCEPROP 1 LAST LOCATION U7
J 0
(-5950 6100);
DISPLAY 1.212766 (-5950 6100);
PAINT GREEN (-5950 6100);
FORCEPROP 0 LAST $SEC 1
J 0
(-5950 6400);
DISPLAY 0.680851 (-5950 6400);
PAINT MONO (-5950 6400);
DISPLAY INVISIBLE (-5950 6400);
FORCEPROP 0 LAST CDS_SEC 1
J 0
(-5950 6400);
DISPLAY 1.021277 (-5950 6400);
DISPLAY INVISIBLE (-5950 6400);
FORCEPROP 0 LASTPIN (-5350 5750) $PN 2
J 0
(-5340 5760);
DISPLAY 0.680851 (-5340 5760);
PAINT MONO (-5340 5760);
FORCEPROP 0 LASTPIN (-6050 5750) $PN 1
J 2
(-6060 5760);
DISPLAY 0.680851 (-6060 5760);
PAINT MONO (-6060 5760);
FORCEPROP 0 LASTPIN (-6050 5850) $PN 3
J 2
(-6060 5860);
DISPLAY 0.680851 (-6060 5860);
PAINT MONO (-6060 5860);
FORCEPROP 0 LASTPIN (-6050 5950) $PN 4
J 2
(-6060 5960);
DISPLAY 0.680851 (-6060 5960);
PAINT MONO (-6060 5960);
FORCEPROP 0 LASTPIN (-5350 5950) $PN 5
J 0
(-5340 5960);
DISPLAY 0.680851 (-5340 5960);
PAINT MONO (-5340 5960);
FORCEPROP 1 LAST CDS_LMAN_SYM_OUTLINE 0,0,500,-400
J 0
(-5950 6050);
DISPLAY 0.468085 (-5950 6050);
PAINT GREEN (-5950 6050);
DISPLAY INVISIBLE (-5950 6050);
FORCEPROP 2 LAST CDS_LIB memory
J 0
(-5950 6050);
DISPLAY INVISIBLE (-5950 6050);
FORCEPROP 1 LAST PATH I89
J 0
(-5900 6100);
DISPLAY 1.212766 (-5900 6100);
PAINT GREEN (-5900 6100);
DISPLAY INVISIBLE (-5900 6100);
FORCEPROP 1 LAST VALUE AT24MAC602-STUM-T
J 0
(-5950 6300);
DISPLAY 1.212766 (-5950 6300);
PAINT GREEN (-5950 6300);
FORCEPROP 1 LAST CLS_PN A221-00002-FB
J 0
(-5950 6200);
DISPLAY 1.212766 (-5950 6200);
PAINT GREEN (-5950 6200);
FORCEADD GND_SG..1
(-8650 9200);
FORCEPROP 3 LASTPIN (-8600 9250) SIG_NAME SG\g
J 0
(-8590 9260);
DISPLAY 0.659574 (-8590 9260);
PAINT MONO (-8590 9260);
DISPLAY INVISIBLE (-8590 9260);
FORCEPROP 1 LAST CDS_LMAN_SYM_OUTLINE 0,0,100,-50
J 0
(-8650 9200);
DISPLAY 0.468085 (-8650 9200);
PAINT GREEN (-8650 9200);
DISPLAY INVISIBLE (-8650 9200);
FORCEPROP 2 LAST CDS_LIB cls
J 0
(-8650 9200);
DISPLAY INVISIBLE (-8650 9200);
FORCEPROP 1 LAST BODY_TYPE PLUMBING
J 0
(-8635 9185);
DISPLAY 0.808511 (-8635 9185);
PAINT GREEN (-8635 9185);
DISPLAY INVISIBLE (-8635 9185);
FORCEPROP 1 LAST PATH I9
J 0
(-8615 9200);
DISPLAY 0.808511 (-8615 9200);
PAINT GREEN (-8615 9200);
DISPLAY INVISIBLE (-8615 9200);
FORCEPROP 1 LAST HDL_POWER SG
J 1
(-8595 9105);
DISPLAY 0.808511 (-8595 9105);
PAINT GREEN (-8595 9105);
FORCEPROP 0 LAST VOLTAGE 0
J 0
(-8550 9200);
DISPLAY 1.021277 (-8550 9200);
FORCEADD RESISTOR..1
(-7500 5850);
FORCEPROP 1 LAST $LOCATION R345
J 2
(-7700 5850);
DISPLAY 1.212766 (-7700 5850);
PAINT GREEN (-7700 5850);
FORCEPROP 0 LAST CDS_LOCATION R345
J 2
(-7700 5850);
DISPLAY 1.212766 (-7700 5850);
PAINT GREEN (-7700 5850);
DISPLAY INVISIBLE (-7700 5850);
FORCEPROP 0 LAST $SEC 1
J 0
(-7400 6000);
DISPLAY 0.680851 (-7400 6000);
PAINT MONO (-7400 6000);
DISPLAY INVISIBLE (-7400 6000);
FORCEPROP 0 LAST CDS_SEC 1
J 0
(-7400 6000);
DISPLAY 1.021277 (-7400 6000);
DISPLAY INVISIBLE (-7400 6000);
FORCEPROP 0 LASTPIN (-7600 5850) $PN 1
J 2
(-7610 5860);
DISPLAY 0.680851 (-7610 5860);
PAINT MONO (-7610 5860);
FORCEPROP 0 LASTPIN (-7350 5850) $PN 2
J 0
(-7340 5860);
DISPLAY 0.680851 (-7340 5860);
PAINT MONO (-7340 5860);
FORCEPROP 1 LAST PATH I90
J 0
(-7697 5955);
DISPLAY 1.212766 (-7697 5955);
PAINT GREEN (-7697 5955);
DISPLAY INVISIBLE (-7697 5955);
FORCEPROP 1 LAST TOLERANCE 1%
J 0
(-7697 6105);
DISPLAY 1.212766 (-7697 6105);
PAINT GREEN (-7697 6105);
DISPLAY INVISIBLE (-7697 6105);
FORCEPROP 2 LAST CDS_LIB passive
J 0
(-7500 5850);
DISPLAY INVISIBLE (-7500 5850);
FORCEPROP 1 LAST CDS_LMAN_SYM_OUTLINE -50,50,100,-50
J 0
(-7500 5850);
DISPLAY 0.468085 (-7500 5850);
PAINT GREEN (-7500 5850);
DISPLAY INVISIBLE (-7500 5850);
FORCEPROP 1 LAST CLS_PN G155-133R0-01
J 0
(-7636 6050);
DISPLAY 1.212766 (-7636 6050);
PAINT GREEN (-7636 6050);
DISPLAY INVISIBLE (-7636 6050);
FORCEPROP 0 LAST PACKAGE 0402
J 0
(-7550 5900);
DISPLAY 1.021277 (-7550 5900);
FORCEPROP 1 LAST VALUE 33OHM
J 0
(-7250 5850);
DISPLAY 1.212766 (-7250 5850);
PAINT GREEN (-7250 5850);
FORCEADD VCC..1
(-4900 6550);
FORCEPROP 3 LASTPIN (-4850 6500) SIG_NAME XP3R3V_FPGA\g
J 0
(-4840 6510);
DISPLAY 0.659574 (-4840 6510);
PAINT MONO (-4840 6510);
DISPLAY INVISIBLE (-4840 6510);
FORCEPROP 2 LAST CDS_LIB cls
J 0
(-4900 6550);
DISPLAY INVISIBLE (-4900 6550);
FORCEPROP 1 LAST CDS_LMAN_SYM_OUTLINE -250,250,250,-250
J 0
(-4900 6550);
DISPLAY 0.468085 (-4900 6550);
PAINT GREEN (-4900 6550);
DISPLAY INVISIBLE (-4900 6550);
FORCEPROP 1 LAST BODY_TYPE PLUMBING
J 0
(-4945 6507);
DISPLAY 0.340426 (-4945 6507);
PAINT GREEN (-4945 6507);
DISPLAY INVISIBLE (-4945 6507);
FORCEPROP 1 LAST PATH I91
J 0
(-4865 6640);
DISPLAY 0.808511 (-4865 6640);
PAINT GREEN (-4865 6640);
DISPLAY INVISIBLE (-4865 6640);
FORCEPROP 0 LAST VOLTAGE 3.3V
J 0
(-5150 6700);
DISPLAY 1.021277 (-5150 6700);
DISPLAY BOTH (-5150 6700);
FORCEPROP 1 LAST HDL_POWER XP3R3V_FPGA
J 1
(-4845 6605);
DISPLAY 1.021277 (-4845 6605);
PAINT GREEN (-4845 6605);
FORCEADD CAPACITOR..2
(-4850 6100);
FORCEPROP 1 LAST $LOCATION C225
J 0
(-4800 5950);
DISPLAY 1.212766 (-4800 5950);
PAINT GREEN (-4800 5950);
FORCEPROP 0 LAST CDS_LOCATION C225
J 0
(-4800 5950);
DISPLAY 1.212766 (-4800 5950);
PAINT GREEN (-4800 5950);
DISPLAY INVISIBLE (-4800 5950);
FORCEPROP 2 LAST $SEC 1
J 0
(-4800 6250);
PAINT MONO (-4800 6250);
DISPLAY INVISIBLE (-4800 6250);
FORCEPROP 2 LAST CDS_SEC 1
J 0
(-4800 6250);
PAINT MONO (-4800 6250);
DISPLAY INVISIBLE (-4800 6250);
FORCEPROP 2 LASTPIN (-4850 6200) $PN 1
R 1
J 0
(-4860 6210);
DISPLAY 0.808511 (-4860 6210);
PAINT MONO (-4860 6210);
FORCEPROP 2 LASTPIN (-4850 5950) $PN 2
R 1
J 2
(-4860 5940);
DISPLAY 0.808511 (-4860 5940);
PAINT MONO (-4860 5940);
FORCEPROP 1 LAST TOLERANCE 10%
J 0
(-5000 6200);
DISPLAY 1.212766 (-5000 6200);
PAINT GREEN (-5000 6200);
DISPLAY INVISIBLE (-5000 6200);
FORCEPROP 1 LAST CDS_LMAN_SYM_OUTLINE -50,0,50,-50
J 0
(-4850 6100);
DISPLAY 0.468085 (-4850 6100);
PAINT GREEN (-4850 6100);
DISPLAY INVISIBLE (-4850 6100);
FORCEPROP 2 LAST CDS_LIB passive
J 0
(-4850 6100);
DISPLAY INVISIBLE (-4850 6100);
FORCEPROP 1 LAST CLS_PN G105-0B104-EK
J 0
(-4950 6150);
DISPLAY 1.212766 (-4950 6150);
PAINT GREEN (-4950 6150);
DISPLAY INVISIBLE (-4950 6150);
FORCEPROP 1 LAST PATH I92
J 0
(-4950 6150);
DISPLAY 1.212766 (-4950 6150);
PAINT GREEN (-4950 6150);
DISPLAY INVISIBLE (-4950 6150);
FORCEPROP 1 LAST VALUE 0.1UF
J 0
(-4800 6150);
DISPLAY 1.212766 (-4800 6150);
PAINT GREEN (-4800 6150);
FORCEPROP 0 LAST PACKAGE 0402
J 0
(-4700 6050);
DISPLAY 1.021277 (-4700 6050);
FORCEPROP 0 LAST VOLTAGE 25V
J 0
(-4750 5850);
DISPLAY 1.021277 (-4750 5850);
FORCEADD GND_SG..1
(-4900 5350);
FORCEPROP 3 LASTPIN (-4850 5400) SIG_NAME SG\g
J 0
(-4840 5410);
DISPLAY 0.659574 (-4840 5410);
PAINT MONO (-4840 5410);
DISPLAY INVISIBLE (-4840 5410);
FORCEPROP 1 LAST PATH I93
J 0
(-4865 5350);
DISPLAY 0.808511 (-4865 5350);
PAINT GREEN (-4865 5350);
DISPLAY INVISIBLE (-4865 5350);
FORCEPROP 1 LAST BODY_TYPE PLUMBING
J 0
(-4885 5335);
DISPLAY 0.808511 (-4885 5335);
PAINT GREEN (-4885 5335);
DISPLAY INVISIBLE (-4885 5335);
FORCEPROP 1 LAST CDS_LMAN_SYM_OUTLINE 0,0,100,-50
J 0
(-4900 5350);
DISPLAY 0.468085 (-4900 5350);
PAINT GREEN (-4900 5350);
DISPLAY INVISIBLE (-4900 5350);
FORCEPROP 2 LAST CDS_LIB cls
J 0
(-4900 5350);
DISPLAY INVISIBLE (-4900 5350);
FORCEPROP 1 LAST HDL_POWER SG
J 1
(-4845 5255);
DISPLAY 0.808511 (-4845 5255);
PAINT GREEN (-4845 5255);
FORCEADD RESISTOR..2
(-9700 6300);
FORCEPROP 1 LAST $LOCATION R1992
J 0
(-9650 6150);
DISPLAY 1.212766 (-9650 6150);
PAINT GREEN (-9650 6150);
FORCEPROP 0 LAST CDS_LOCATION R1992
J 0
(-9650 6150);
DISPLAY 1.212766 (-9650 6150);
PAINT GREEN (-9650 6150);
DISPLAY INVISIBLE (-9650 6150);
FORCEPROP 0 LAST $SEC 1
J 0
(-9650 6400);
DISPLAY 0.680851 (-9650 6400);
PAINT MONO (-9650 6400);
DISPLAY INVISIBLE (-9650 6400);
FORCEPROP 0 LAST CDS_SEC 1
J 0
(-9650 6400);
DISPLAY 1.021277 (-9650 6400);
DISPLAY INVISIBLE (-9650 6400);
FORCEPROP 0 LASTPIN (-9700 6400) $PN 1
R 1
J 0
(-9710 6410);
DISPLAY 0.680851 (-9710 6410);
PAINT MONO (-9710 6410);
FORCEPROP 0 LASTPIN (-9700 6150) $PN 2
R 1
J 2
(-9710 6140);
DISPLAY 0.680851 (-9710 6140);
PAINT MONO (-9710 6140);
FORCEPROP 1 LAST CLS_PN G155-14701-01
J 0
(-9836 6500);
DISPLAY 1.212766 (-9836 6500);
PAINT GREEN (-9836 6500);
DISPLAY INVISIBLE (-9836 6500);
FORCEPROP 2 LAST CDS_LIB passive
J 0
(-9700 6300);
DISPLAY INVISIBLE (-9700 6300);
FORCEPROP 1 LAST CDS_LMAN_SYM_OUTLINE -50,50,50,-100
J 0
(-9700 6300);
DISPLAY 0.468085 (-9700 6300);
PAINT GREEN (-9700 6300);
DISPLAY INVISIBLE (-9700 6300);
FORCEPROP 1 LAST TOLERANCE 1%
J 0
(-9897 6555);
DISPLAY 1.212766 (-9897 6555);
PAINT GREEN (-9897 6555);
DISPLAY INVISIBLE (-9897 6555);
FORCEPROP 1 LAST PATH I94
J 0
(-9897 6405);
DISPLAY 1.212766 (-9897 6405);
PAINT GREEN (-9897 6405);
DISPLAY INVISIBLE (-9897 6405);
FORCEPROP 1 LAST VALUE 4.7KOHM
J 0
(-9650 6350);
DISPLAY 0.787234 (-9650 6350);
PAINT GREEN (-9650 6350);
FORCEPROP 0 LAST PACKAGE 0402
J 0
(-9650 6450);
DISPLAY 1.021277 (-9650 6450);
FORCEADD RESISTOR..2
(-8900 6300);
FORCEPROP 1 LAST $LOCATION R19
J 0
(-8850 6150);
DISPLAY 1.212766 (-8850 6150);
PAINT GREEN (-8850 6150);
FORCEPROP 0 LAST CDS_LOCATION R19
J 0
(-8850 6150);
DISPLAY 1.212766 (-8850 6150);
PAINT GREEN (-8850 6150);
DISPLAY INVISIBLE (-8850 6150);
FORCEPROP 0 LAST $SEC 1
J 0
(-8850 6400);
DISPLAY 0.680851 (-8850 6400);
PAINT MONO (-8850 6400);
DISPLAY INVISIBLE (-8850 6400);
FORCEPROP 0 LAST CDS_SEC 1
J 0
(-8850 6400);
DISPLAY 1.021277 (-8850 6400);
DISPLAY INVISIBLE (-8850 6400);
FORCEPROP 0 LASTPIN (-8900 6400) $PN 1
R 1
J 0
(-8910 6410);
DISPLAY 0.680851 (-8910 6410);
PAINT MONO (-8910 6410);
FORCEPROP 0 LASTPIN (-8900 6150) $PN 2
R 1
J 2
(-8910 6140);
DISPLAY 0.680851 (-8910 6140);
PAINT MONO (-8910 6140);
FORCEPROP 1 LAST CDS_LMAN_SYM_OUTLINE -50,50,50,-100
J 0
(-8900 6300);
DISPLAY 0.468085 (-8900 6300);
PAINT GREEN (-8900 6300);
DISPLAY INVISIBLE (-8900 6300);
FORCEPROP 2 LAST CDS_LIB passive
J 0
(-8900 6300);
DISPLAY INVISIBLE (-8900 6300);
FORCEPROP 1 LAST TOLERANCE 1%
J 0
(-9097 6555);
DISPLAY 1.212766 (-9097 6555);
PAINT GREEN (-9097 6555);
DISPLAY INVISIBLE (-9097 6555);
FORCEPROP 1 LAST PATH I95
J 0
(-9097 6405);
DISPLAY 1.212766 (-9097 6405);
PAINT GREEN (-9097 6405);
DISPLAY INVISIBLE (-9097 6405);
FORCEPROP 1 LAST CLS_PN G155-11002-01
J 0
(-9036 6500);
DISPLAY 1.212766 (-9036 6500);
PAINT GREEN (-9036 6500);
DISPLAY INVISIBLE (-9036 6500);
FORCEPROP 0 LAST PACKAGE 0402
J 0
(-8850 6450);
DISPLAY 1.021277 (-8850 6450);
FORCEPROP 1 LAST VALUE 10KOHM
J 0
(-8850 6350);
DISPLAY 0.787234 (-8850 6350);
PAINT GREEN (-8850 6350);
FORCEADD RESISTOR..2
(-9250 6300);
FORCEPROP 1 LAST $LOCATION R1991
J 0
(-9200 6150);
DISPLAY 1.212766 (-9200 6150);
PAINT GREEN (-9200 6150);
FORCEPROP 0 LAST CDS_LOCATION R1991
J 0
(-9200 6150);
DISPLAY 1.212766 (-9200 6150);
PAINT GREEN (-9200 6150);
DISPLAY INVISIBLE (-9200 6150);
FORCEPROP 0 LAST $SEC 1
J 0
(-9200 6400);
DISPLAY 0.680851 (-9200 6400);
PAINT MONO (-9200 6400);
DISPLAY INVISIBLE (-9200 6400);
FORCEPROP 0 LAST CDS_SEC 1
J 0
(-9200 6400);
DISPLAY 1.021277 (-9200 6400);
DISPLAY INVISIBLE (-9200 6400);
FORCEPROP 0 LASTPIN (-9250 6400) $PN 1
R 1
J 0
(-9260 6410);
DISPLAY 0.680851 (-9260 6410);
PAINT MONO (-9260 6410);
FORCEPROP 0 LASTPIN (-9250 6150) $PN 2
R 1
J 2
(-9260 6140);
DISPLAY 0.680851 (-9260 6140);
PAINT MONO (-9260 6140);
FORCEPROP 2 LAST CDS_LIB passive
J 0
(-9250 6300);
DISPLAY INVISIBLE (-9250 6300);
FORCEPROP 1 LAST CDS_LMAN_SYM_OUTLINE -50,50,50,-100
J 0
(-9250 6300);
DISPLAY 0.468085 (-9250 6300);
PAINT GREEN (-9250 6300);
DISPLAY INVISIBLE (-9250 6300);
FORCEPROP 1 LAST TOLERANCE 1%
J 0
(-9447 6555);
DISPLAY 1.212766 (-9447 6555);
PAINT GREEN (-9447 6555);
DISPLAY INVISIBLE (-9447 6555);
FORCEPROP 1 LAST PATH I96
J 0
(-9447 6405);
DISPLAY 1.212766 (-9447 6405);
PAINT GREEN (-9447 6405);
DISPLAY INVISIBLE (-9447 6405);
FORCEPROP 1 LAST CLS_PN G155-11002-01
J 0
(-9386 6500);
DISPLAY 1.212766 (-9386 6500);
PAINT GREEN (-9386 6500);
DISPLAY INVISIBLE (-9386 6500);
FORCEPROP 0 LAST PACKAGE 0402
J 0
(-9200 6450);
DISPLAY 1.021277 (-9200 6450);
FORCEPROP 1 LAST VALUE 10KOHM
J 0
(-9200 6350);
DISPLAY 0.787234 (-9200 6350);
PAINT GREEN (-9200 6350);
FORCEADD RESISTOR..2
(-9750 5300);
FORCEPROP 1 LAST $LOCATION R344
J 0
(-10050 5100);
DISPLAY 1.212766 (-10050 5100);
PAINT GREEN (-10050 5100);
FORCEPROP 0 LAST CDS_LOCATION R344
J 0
(-9700 5150);
DISPLAY 1.212766 (-9700 5150);
PAINT GREEN (-9700 5150);
DISPLAY INVISIBLE (-9700 5150);
FORCEPROP 2 LAST $SEC 1
J 0
(-9700 5500);
DISPLAY 0.680851 (-9700 5500);
PAINT MONO (-9700 5500);
DISPLAY INVISIBLE (-9700 5500);
FORCEPROP 2 LAST CDS_SEC 1
J 0
(-9700 5500);
DISPLAY 1.021277 (-9700 5500);
DISPLAY INVISIBLE (-9700 5500);
FORCEPROP 2 LASTPIN (-9750 5400) $PN 1
R 1
J 0
(-9760 5410);
DISPLAY 0.808511 (-9760 5410);
FORCEPROP 2 LASTPIN (-9750 5150) $PN 2
R 1
J 2
(-9760 5140);
DISPLAY 0.808511 (-9760 5140);
FORCEPROP 1 LAST PATH I97
J 0
(-9947 5405);
DISPLAY 1.212766 (-9947 5405);
PAINT GREEN (-9947 5405);
DISPLAY INVISIBLE (-9947 5405);
FORCEPROP 1 LAST TOLERANCE 1%
J 0
(-9947 5555);
DISPLAY 1.212766 (-9947 5555);
PAINT GREEN (-9947 5555);
DISPLAY INVISIBLE (-9947 5555);
FORCEPROP 1 LAST CDS_LMAN_SYM_OUTLINE -50,50,50,-100
J 0
(-9750 5300);
DISPLAY 0.468085 (-9750 5300);
PAINT GREEN (-9750 5300);
DISPLAY INVISIBLE (-9750 5300);
FORCEPROP 2 LAST CDS_LIB passive
J 0
(-9750 5300);
DISPLAY INVISIBLE (-9750 5300);
FORCEPROP 1 LAST CLS_PN G155-14701-01
J 0
(-9886 5500);
DISPLAY 1.212766 (-9886 5500);
PAINT GREEN (-9886 5500);
DISPLAY INVISIBLE (-9886 5500);
FORCEPROP 0 LAST NO_ASSY TRUE
J 0
(-9700 5250);
DISPLAY 0.808511 (-9700 5250);
DISPLAY BOTH (-9700 5250);
FORCEPROP 0 LAST PACKAGE 0402
J 0
(-10050 5200);
DISPLAY 0.808511 (-10050 5200);
FORCEPROP 1 LAST VALUE 4.7KOHM
J 0
(-10200 5300);
DISPLAY 1.212766 (-10200 5300);
PAINT GREEN (-10200 5300);
FORCEADD GND_SG..1
(-9800 4950);
FORCEPROP 3 LASTPIN (-9750 5000) SIG_NAME SG\g
J 0
(-9740 5010);
DISPLAY 0.659574 (-9740 5010);
PAINT MONO (-9740 5010);
DISPLAY INVISIBLE (-9740 5010);
FORCEPROP 2 LAST CDS_LIB cls
J 0
(-9800 4950);
DISPLAY INVISIBLE (-9800 4950);
FORCEPROP 1 LAST CDS_LMAN_SYM_OUTLINE 0,0,100,-50
J 0
(-9800 4950);
DISPLAY 0.468085 (-9800 4950);
PAINT GREEN (-9800 4950);
DISPLAY INVISIBLE (-9800 4950);
FORCEPROP 1 LAST BODY_TYPE PLUMBING
J 0
(-9785 4935);
DISPLAY 0.808511 (-9785 4935);
PAINT GREEN (-9785 4935);
DISPLAY INVISIBLE (-9785 4935);
FORCEPROP 1 LAST PATH I98
J 0
(-9765 4950);
DISPLAY 0.808511 (-9765 4950);
PAINT GREEN (-9765 4950);
DISPLAY INVISIBLE (-9765 4950);
FORCEPROP 1 LAST HDL_POWER SG
J 1
(-9745 4855);
DISPLAY 0.808511 (-9745 4855);
PAINT GREEN (-9745 4855);
FORCEADD VCC..1
(-9750 6750);
FORCEPROP 3 LASTPIN (-9700 6700) SIG_NAME XP3R3V_FPGA\g
J 0
(-9690 6710);
DISPLAY 0.659574 (-9690 6710);
PAINT MONO (-9690 6710);
DISPLAY INVISIBLE (-9690 6710);
FORCEPROP 1 LAST CDS_LMAN_SYM_OUTLINE -250,250,250,-250
J 0
(-9750 6750);
DISPLAY 0.468085 (-9750 6750);
PAINT GREEN (-9750 6750);
DISPLAY INVISIBLE (-9750 6750);
FORCEPROP 2 LAST CDS_LIB cls
J 0
(-9750 6750);
DISPLAY INVISIBLE (-9750 6750);
FORCEPROP 1 LAST BODY_TYPE PLUMBING
J 0
(-9795 6707);
DISPLAY 0.340426 (-9795 6707);
PAINT GREEN (-9795 6707);
DISPLAY INVISIBLE (-9795 6707);
FORCEPROP 1 LAST PATH I99
J 0
(-9715 6840);
DISPLAY 0.808511 (-9715 6840);
PAINT GREEN (-9715 6840);
DISPLAY INVISIBLE (-9715 6840);
FORCEPROP 0 LAST VOLTAGE 3.3V
J 0
(-10000 6900);
DISPLAY 1.021277 (-10000 6900);
DISPLAY BOTH (-10000 6900);
FORCEPROP 1 LAST HDL_POWER XP3R3V_FPGA
J 1
(-9695 6805);
DISPLAY 1.021277 (-9695 6805);
PAINT GREEN (-9695 6805);
FORCEADD SHEET_A1..1
(550 1900);
FORCEPROP 2 LAST CUSTOM_TXT_CDS <XR_PAGE_TITLE>
J 0
(-15020 13250);
DISPLAY 0.638298 (-15020 13250);
PAINT PINK (-15020 13250);
FORCEPROP 1 LAST CUSTOM_TXT_CDS <DOCNO>
J 0
(-1500 2285);
DISPLAY 0.978723 (-1500 2285);
FORCEPROP 1 LAST CUSTOM_TXT_CDS <CON_PAGE_NUM>
J 0
(-1605 1950);
DISPLAY 0.978723 (-1605 1950);
FORCEPROP 1 LAST CUSTOM_TXT_CDS <DATE>
J 0
(-150 2075);
DISPLAY 0.978723 (-150 2075);
FORCEPROP 1 LAST CUSTOM_TXT_CDS <TITLE>
J 1
(-1235 2530);
DISPLAY 0.978723 (-1235 2530);
FORCEPROP 1 LAST CUSTOM_TXT_CDS <DESIGNER>
J 0
(-150 2500);
DISPLAY 0.978723 (-150 2500);
FORCEPROP 1 LAST CUSTOM_TXT_CDS <CON_TOTAL_PAGES>
J 0
(-1295 1950);
DISPLAY 0.808511 (-1295 1950);
FORCEPROP 1 LAST CUSTOM_TXT_CDS <ASSY_PN>
J 0
(-1500 2075);
DISPLAY 0.978723 (-1500 2075);
FORCEPROP 1 LAST CUSTOM_TXT_CDS <DOCREV>
J 0
(-150 2275);
DISPLAY 0.978723 (-150 2275);
FORCEPROP 1 LAST COMMENT_BODY TRUE
J 0
(560 1955);
DISPLAY 0.808511 (560 1955);
DISPLAY INVISIBLE (560 1955);
FORCEPROP 2 LAST PAGE_BORDER TRUE
J 0
(-15020 13250);
DISPLAY 0.638298 (-15020 13250);
PAINT PINK (-15020 13250);
DISPLAY INVISIBLE (-15020 13250);
FORCEPROP 1 LAST CDS_LMAN_SYM_OUTLINE -15850,11500,200,-200
J 0
(550 1900);
DISPLAY 0.468085 (550 1900);
PAINT GREEN (550 1900);
DISPLAY INVISIBLE (550 1900);
FORCEPROP 2 LAST CDS_LIB cls
J 0
(550 1900);
DISPLAY INVISIBLE (550 1900);
FORCEPROP 1 LAST TITLE I2C_SWITCH&EEPROM
J 0
(-1950 2750);
DISPLAY 3.042553 (-1950 2750);
PAINT GREEN (-1950 2750);
FORCEPROP 2 LAST CDS_XR_PAGE_TITLE CR-16 : @TIMECARD_LIB.TIMECARD(SCH_1):PAGE16
J 0
(-15020 13250);
DISPLAY 0.638298 (-15020 13250);
PAINT PINK (-15020 13250);
DISPLAY INVISIBLE (-15020 13250);
WIRE 16 -1 (-6050 5850)(-7350 5850);
FORCEPROP 2 LAST SIG_NAME PRI_EEPROM_SDA
J 0
(-6910 5860);
DISPLAY 1.021277 (-6910 5860);
WIRE 16 -1 (-11400 4300)(-9850 4300);
FORCEPROP 2 LAST SIG_NAME FPGA_OUT_SEC_EEPROM_WP
J 0
(-11310 4310);
DISPLAY 1.021277 (-11310 4310);
WIRE 16 -1 (-12650 5750)(-11100 5750);
FORCEPROP 2 LAST SIG_NAME EEPROM_I2C_SCL
J 0
(-12610 5760);
DISPLAY 1.021277 (-12610 5760);
WIRE 16 -1 (-11400 10800)(-9850 10800);
FORCEPROP 2 LAST SIG_NAME FPGA_OUT_PCA9546_RST_N
J 0
(-11360 10810);
DISPLAY 1.021277 (-11360 10810);
WIRE 16 -1 (-11400 10500)(-9850 10500);
FORCEPROP 2 LAST SIG_NAME PCA9546_I2C_SDA
J 0
(-11360 10510);
DISPLAY 1.021277 (-11360 10510);
WIRE 16 -1 (-11400 10400)(-9850 10400);
FORCEPROP 2 LAST SIG_NAME PCA9546_I2C_SCL
J 0
(-11360 10410);
DISPLAY 1.021277 (-11360 10410);
WIRE 16 -1 (-11400 10200)(-9850 10200);
FORCEPROP 2 LAST SIG_NAME PCIE_SMDAT
J 0
(-11360 10210);
DISPLAY 1.021277 (-11360 10210);
WIRE 16 -1 (-11400 10100)(-9850 10100);
FORCEPROP 2 LAST SIG_NAME PCIE_SMCLK
J 0
(-11360 10110);
DISPLAY 1.021277 (-11360 10110);
WIRE 16 -1 (-7950 11050)(-7050 11050);
WIRE 16 -1 (-7050 11050)(-7050 10500);
WIRE 16 -1 (-6650 10500)(-7050 10500);
WIRE 16 -1 (-8900 10500)(-7050 10500);
FORCEPROP 2 LAST SIG_NAME R_PCA9546_I2C_SDA
J 0
(-8310 10510);
DISPLAY 1.021277 (-8310 10510);
WIRE 16 -1 (-9600 10500)(-8900 10500);
WIRE 16 -1 (-8900 10500)(-8900 10200);
WIRE 16 -1 (-8900 10200)(-8900 9900);
WIRE 16 -1 (-9600 10200)(-8900 10200);
WIRE 16 -1 (-8900 9900)(-8900 9350);
WIRE 16 -1 (-8900 9900)(-9600 9900);
WIRE 16 -1 (-9400 9350)(-8900 9350);
WIRE 16 -1 (-7950 10950)(-7100 10950);
WIRE 16 -1 (-7100 10950)(-7100 10400);
WIRE 16 -1 (-6650 10400)(-7100 10400);
WIRE 16 -1 (-8850 10400)(-7100 10400);
FORCEPROP 2 LAST SIG_NAME R_PCA9546_I2C_SCL
J 0
(-8310 10410);
DISPLAY 1.021277 (-8310 10410);
WIRE 16 -1 (-9600 10400)(-8850 10400);
WIRE 16 -1 (-8850 10400)(-8850 10100);
WIRE 16 -1 (-8850 10100)(-8850 9800);
WIRE 16 -1 (-9600 10100)(-8850 10100);
WIRE 16 -1 (-8850 9800)(-8850 9250);
WIRE 16 -1 (-8850 9800)(-9600 9800);
WIRE 16 -1 (-8850 9250)(-9400 9250);
WIRE 16 -1 (-7650 10800)(-7650 10700);
WIRE 16 -1 (-9600 10800)(-7650 10800);
FORCEPROP 2 LAST SIG_NAME PCA9546_RST_N
J 0
(-8310 10810);
DISPLAY 1.021277 (-8310 10810);
WIRE 16 -1 (-7650 10800)(-6950 10800);
WIRE 16 -1 (-7650 10700)(-7750 10700);
WIRE 16 -1 (-6950 11150)(-6950 10800);
WIRE 16 -1 (-6950 10800)(-6900 10800);
WIRE 16 -1 (-6650 10800)(-6900 10800);
WIRE 16 -1 (-6900 9350)(-6900 10800);
WIRE 16 -1 (-7950 11150)(-6950 11150);
WIRE 16 -1 (-6900 9350)(-7950 9350);
WIRE 16 -1 (-9650 9350)(-10050 9350);
WIRE 16 -1 (-10050 9250)(-9650 9250);
WIRE 16 -1 (-4650 4650)(-4650 4500);
WIRE 16 -1 (-4650 4500)(-4650 4300);
WIRE 16 -1 (-4650 4500)(-5350 4500);
WIRE 16 -1 (-4200 4650)(-4200 4400);
WIRE 16 -1 (-4200 4400)(-4200 4300);
WIRE 16 -1 (-4200 4400)(-5350 4400);
WIRE 16 -1 (-5750 9900)(-3600 9900);
FORCEPROP 2 LAST SIG_NAME BNO080_I2C_SDA
J 0
(-4310 9910);
DISPLAY 1.021277 (-4310 9910);
WIRE 16 -1 (-5750 9800)(-3600 9800);
FORCEPROP 2 LAST SIG_NAME BNO080_I2C_SCL
J 0
(-4310 9810);
DISPLAY 1.021277 (-4310 9810);
WIRE 16 -1 (-11400 9900)(-9850 9900);
FORCEPROP 2 LAST SIG_NAME RGB_LED_I2C_SDA
J 0
(-11360 9910);
DISPLAY 1.021277 (-11360 9910);
WIRE 16 -1 (-12650 6350)(-11100 6350);
FORCEPROP 2 LAST SIG_NAME RGB_LED_I2C_SDA
J 0
(-12610 6360);
DISPLAY 1.021277 (-12610 6360);
WIRE 16 -1 (-11100 5850)(-12650 5850);
FORCEPROP 2 LAST SIG_NAME EEPROM_I2C_SDA
J 0
(-12610 5860);
DISPLAY 1.021277 (-12610 5860);
WIRE 16 -1 (-7100 10100)(-7100 9700);
WIRE 16 -1 (-7950 10100)(-7100 10100);
WIRE 16 -1 (-6650 10100)(-7100 10100);
WIRE 16 -1 (-7100 9700)(-7950 9700);
WIRE 16 -1 (-7950 9500)(-7000 9500);
WIRE 16 -1 (-7000 9500)(-7000 9900);
WIRE 16 -1 (-7950 9900)(-7000 9900);
WIRE 16 -1 (-6650 9900)(-7000 9900);
WIRE 16 -1 (-7950 9600)(-7050 9600);
WIRE 16 -1 (-7050 9600)(-7050 10000);
WIRE 16 -1 (-7050 10000)(-6650 10000);
WIRE 16 -1 (-7950 10000)(-7050 10000);
WIRE 16 -1 (-6050 4600)(-7350 4600);
FORCEPROP 2 LAST SIG_NAME SEC_EEPROM_SDA
J 0
(-6910 4610);
DISPLAY 1.021277 (-6910 4610);
WIRE 16 -1 (-12650 6100)(-11100 6100);
FORCEPROP 2 LAST SIG_NAME PCIE_SMDAT
J 0
(-12610 6110);
DISPLAY 1.021277 (-12610 6110);
WIRE 16 -1 (-11400 9250)(-10550 9250);
FORCEPROP 2 LAST SIG_NAME EEPROM_SCL
J 0
(-11360 9260);
DISPLAY 1.021277 (-11360 9260);
WIRE 16 -1 (-5850 9000)(-5850 9200);
WIRE 16 -1 (-5850 9200)(-5850 9350);
WIRE 16 -1 (-5250 9200)(-5850 9200);
WIRE 16 -1 (-5250 9350)(-5850 9350);
WIRE 16 -1 (-5850 9350)(-6250 9350);
FORCEPROP 2 LAST SIG_NAME VDD_PCA9546A
J 0
(-6210 9360);
DISPLAY 1.021277 (-6210 9360);
WIRE 16 -1 (-6250 9250)(-6250 9350);
WIRE 16 -1 (-5750 10100)(-3600 10100);
FORCEPROP 2 LAST SIG_NAME ICP10100_I2C_SCL
J 0
(-4410 10110);
DISPLAY 1.021277 (-4410 10110);
WIRE 16 -1 (-5750 10200)(-3600 10200);
FORCEPROP 2 LAST SIG_NAME ICP10100_I2C_SDA
J 0
(-4410 10210);
DISPLAY 1.021277 (-4410 10210);
WIRE 16 -1 (-5750 10400)(-3600 10400);
FORCEPROP 2 LAST SIG_NAME SHT3X_I2C_SCL
J 0
(-4260 10410);
DISPLAY 1.021277 (-4260 10410);
WIRE 16 -1 (-5750 10500)(-3600 10500);
FORCEPROP 2 LAST SIG_NAME SHT3X_I2C_SDA
J 0
(-4260 10510);
DISPLAY 1.021277 (-4260 10510);
WIRE 16 -1 (-5750 10700)(-3600 10700);
FORCEPROP 2 LAST SIG_NAME LM75B_I2C_SCL
J 0
(-4260 10710);
DISPLAY 1.021277 (-4260 10710);
WIRE 16 -1 (-5750 10800)(-3600 10800);
FORCEPROP 2 LAST SIG_NAME LM75B_I2C_SDA
J 0
(-4260 10810);
DISPLAY 1.021277 (-4260 10810);
WIRE 16 -1 (-11400 9350)(-10550 9350);
FORCEPROP 2 LAST SIG_NAME EEPROM_SDA
J 0
(-11360 9360);
DISPLAY 1.021277 (-11360 9360);
WIRE 16 -1 (-5100 4650)(-5100 4600);
WIRE 16 -1 (-5100 4600)(-5100 4300);
WIRE 16 -1 (-5100 4600)(-5350 4600);
WIRE 16 -1 (-11400 9800)(-9850 9800);
FORCEPROP 2 LAST SIG_NAME RGB_LED_I2C_SCL
J 0
(-11360 9810);
DISPLAY 1.021277 (-11360 9810);
WIRE 16 -1 (-12650 6250)(-11100 6250);
FORCEPROP 2 LAST SIG_NAME RGB_LED_I2C_SCL
J 0
(-12610 6260);
DISPLAY 1.021277 (-12610 6260);
WIRE 16 273 (-300 7800)(-14050 7800);
WIRE 16 -1 (-1900 5450)(-1900 5550);
WIRE 16 -1 (-1900 5300)(-1900 5450);
WIRE 16 -1 (-2050 5450)(-1900 5450);
WIRE 16 -1 (-1900 5550)(-2050 5550);
WIRE 16 -1 (-4200 3950)(-4200 3900);
WIRE 16 -1 (-4200 4050)(-4200 3950);
WIRE 16 -1 (-4200 3950)(-4650 3950);
WIRE 16 -1 (-4650 4050)(-4650 3950);
WIRE 16 -1 (-4650 3950)(-5100 3950);
WIRE 16 -1 (-5100 4050)(-5100 3950);
WIRE 16 -1 (-2350 3750)(-2350 3800);
WIRE 16 -1 (-1850 3800)(-2350 3800);
WIRE 16 -1 (-2350 3800)(-2350 3850);
WIRE 16 -1 (-1850 4100)(-1850 3800);
WIRE 16 -1 (-4200 5000)(-4200 4950);
WIRE 16 -1 (-4200 4950)(-4200 4900);
WIRE 16 -1 (-4650 4950)(-4200 4950);
WIRE 16 -1 (-4650 4950)(-4650 4900);
WIRE 16 -1 (-5100 4950)(-4650 4950);
WIRE 16 -1 (-5100 4900)(-5100 4950);
WIRE 16 -1 (-8900 4750)(-8900 4900);
WIRE 16 -1 (-8850 3650)(-8850 3850);
WIRE 16 -1 (-2350 4650)(-2350 4600);
WIRE 16 -1 (-2350 4600)(-1850 4600);
WIRE 16 -1 (-2350 4550)(-2350 4600);
WIRE 16 -1 (-1850 4600)(-1850 4350);
WIRE 16 -1 (-6250 8450)(-5850 8450);
WIRE 16 -1 (-6250 8550)(-6250 8450);
WIRE 16 -1 (-6250 8450)(-6250 8350);
WIRE 16 -1 (-5850 8750)(-5850 8450);
WIRE 16 -1 (-3750 9200)(-3750 9400);
WIRE 16 -1 (-5000 9200)(-3750 9200);
WIRE 16 -1 (-8650 11250)(-8650 11150);
WIRE 16 -1 (-8200 11150)(-8650 11150);
WIRE 16 -1 (-8650 11150)(-8650 11050);
WIRE 16 -1 (-8200 11050)(-8650 11050);
WIRE 16 -1 (-8650 10950)(-8650 11050);
WIRE 16 -1 (-8200 10950)(-8650 10950);
WIRE 16 -1 (-8650 10100)(-8650 10950);
WIRE 16 -1 (-8200 10100)(-8650 10100);
WIRE 16 -1 (-8650 10000)(-8650 10100);
WIRE 16 -1 (-8200 10000)(-8650 10000);
WIRE 16 -1 (-8650 9900)(-8650 10000);
WIRE 16 -1 (-8200 9900)(-8650 9900);
WIRE 16 -1 (-4400 9350)(-4400 9400);
WIRE 16 -1 (-4400 9350)(-5000 9350);
WIRE 16 -1 (-8600 9250)(-8600 9350);
WIRE 16 -1 (-8200 9350)(-8600 9350);
WIRE 16 -1 (-8600 9500)(-8600 9350);
WIRE 16 -1 (-8200 9500)(-8600 9500);
WIRE 16 -1 (-8600 9500)(-8600 9600);
WIRE 16 -1 (-8200 9600)(-8600 9600);
WIRE 16 -1 (-8600 9600)(-8600 9700);
WIRE 16 -1 (-8200 9700)(-8600 9700);
WIRE 16 -1 (-4850 6500)(-4850 6400);
WIRE 16 -1 (-4850 6200)(-4850 6400);
WIRE 16 -1 (-6150 6400)(-4850 6400);
WIRE 16 -1 (-6150 5950)(-6150 6400);
WIRE 16 -1 (-6150 5950)(-6050 5950);
WIRE 16 -1 (-5350 5750)(-4850 5750);
WIRE 16 -1 (-4850 5950)(-4850 5750);
WIRE 16 -1 (-4850 5400)(-4850 5750);
WIRE 16 -1 (-9700 6600)(-9700 6700);
WIRE 16 -1 (-9700 6600)(-9250 6600);
WIRE 16 -1 (-9700 6400)(-9700 6600);
WIRE 16 -1 (-8900 6600)(-9250 6600);
WIRE 16 -1 (-9250 6400)(-9250 6600);
WIRE 16 -1 (-8900 6400)(-8900 6600);
WIRE 16 -1 (-12650 5550)(-11100 5550);
FORCEPROP 2 LAST SIG_NAME FPGA_OUT_SN_EEPROM_WP
J 0
(-12610 5560);
DISPLAY 1.021277 (-12610 5560);
WIRE 16 -1 (-9750 5000)(-9750 5150);
WIRE 16 -1 (-9600 4300)(-8900 4300);
WIRE 16 -1 (-8900 4500)(-8900 4300);
WIRE 16 -1 (-8850 4300)(-8900 4300);
WIRE 16 -1 (-6150 4300)(-8850 4300);
WIRE 16 -1 (-8850 4300)(-8850 4100);
WIRE 16 -1 (-6150 4300)(-6050 4300);
WIRE 16 -1 (-6150 3650)(-6150 4300);
WIRE 16 -1 (-3650 3650)(-6150 3650);
WIRE 16 -1 (-3650 3650)(-3650 5400);
WIRE 16 -1 (-3650 5400)(-3650 5450);
WIRE 16 -1 (-3850 5400)(-3650 5400);
WIRE 16 -1 (-2550 5450)(-3650 5450);
FORCEPROP 2 LAST SIG_NAME SEC_EEPROM_WP
J 0
(-3460 5460);
DISPLAY 1.021277 (-3460 5460);
WIRE 16 -1 (-10850 5550)(-9750 5550);
WIRE 16 -1 (-9700 5550)(-9750 5550);
WIRE 16 -1 (-9750 5400)(-9750 5550);
WIRE 16 -1 (-5200 5550)(-9700 5550);
WIRE 16 -1 (-9700 6150)(-9700 5550);
WIRE 16 -1 (-5200 5950)(-5200 5550);
WIRE 16 -1 (-5200 5550)(-3700 5550);
WIRE 16 -1 (-3700 5550)(-3700 5450);
WIRE 16 -1 (-3700 5550)(-2550 5550);
FORCEPROP 2 LAST SIG_NAME SN_EEPROM_WP
J 0
(-3410 5560);
DISPLAY 1.021277 (-3410 5560);
WIRE 16 -1 (-5350 5950)(-5200 5950);
WIRE 16 -1 (-3700 5450)(-3850 5450);
WIRE 16 -1 (-10850 6250)(-10000 6250);
WIRE 16 -1 (-10000 6250)(-10000 6000);
WIRE 16 -1 (-10850 6000)(-10000 6000);
WIRE 16 -1 (-10000 5750)(-10000 6000);
WIRE 16 -1 (-10850 5750)(-10000 5750);
WIRE 16 -1 (-10000 5750)(-8900 5750);
WIRE 16 -1 (-8900 5750)(-8050 5750);
FORCEPROP 2 LAST SIG_NAME EEPROM_SCL
J 0
(-8810 5760);
DISPLAY 1.021277 (-8810 5760);
WIRE 16 -1 (-8900 6150)(-8900 5750);
WIRE 16 -1 (-6050 5750)(-8050 5750);
WIRE 16 -1 (-8050 5750)(-8050 4500);
WIRE 16 -1 (-8100 4500)(-8050 4500);
WIRE 16 -1 (-6050 4500)(-8050 4500);
WIRE 16 -1 (-8100 4600)(-8000 4600);
WIRE 16 -1 (-8000 5850)(-8000 4600);
WIRE 16 -1 (-7600 4600)(-8000 4600);
WIRE 16 -1 (-7600 5850)(-8000 5850);
WIRE 16 -1 (-9250 5850)(-8000 5850);
FORCEPROP 2 LAST SIG_NAME EEPROM_SDA
J 0
(-8810 5860);
DISPLAY 1.021277 (-8810 5860);
WIRE 16 -1 (-9250 6150)(-9250 5850);
WIRE 16 -1 (-9950 5850)(-9250 5850);
WIRE 16 -1 (-9950 5850)(-9950 6100);
WIRE 16 -1 (-10850 5850)(-9950 5850);
WIRE 16 -1 (-9950 6350)(-9950 6100);
WIRE 16 -1 (-10850 6100)(-9950 6100);
WIRE 16 -1 (-10850 6350)(-9950 6350);
WIRE 16 -1 (-11100 6000)(-12650 6000);
FORCEPROP 2 LAST SIG_NAME PCIE_SMCLK
J 0
(-12610 6010);
DISPLAY 1.021277 (-12610 6010);
DOT 1 (-8900 5750);
DOT 1 (-7650 10800);
DOT 1 (-8650 11050);
DOT 1 (-8650 10950);
DOT 1 (-8650 11150);
DOT 1 (-3650 5400);
DOT 1 (-8000 5850);
DOT 1 (-8900 4300);
DOT 1 (-8050 4500);
DOT 1 (-1900 5450);
DOT 1 (-9250 5850);
DOT 1 (-9250 6600);
DOT 1 (-9750 5550);
DOT 1 (-9700 5550);
DOT 1 (-8000 4600);
DOT 1 (-8050 5750);
DOT 1 (-8850 4300);
DOT 1 (-4200 3950);
DOT 1 (-6150 4300);
DOT 1 (-5100 4600);
DOT 1 (-5200 5550);
DOT 1 (-4650 4500);
DOT 1 (-4650 4950);
DOT 1 (-4200 4400);
DOT 1 (-4200 4950);
DOT 1 (-4850 5750);
DOT 1 (-4850 6400);
DOT 1 (-2350 3800);
DOT 1 (-2350 4600);
DOT 1 (-4650 3950);
DOT 1 (-9700 6600);
DOT 1 (-8900 9900);
DOT 1 (-8600 9350);
DOT 1 (-8600 9500);
DOT 1 (-8850 9800);
DOT 1 (-8650 10000);
DOT 1 (-8600 9600);
DOT 1 (-8850 10100);
DOT 1 (-8650 10100);
DOT 1 (-8900 10200);
DOT 1 (-8850 10400);
DOT 1 (-7050 10000);
DOT 1 (-7000 9900);
DOT 1 (-6250 8450);
DOT 1 (-5850 9350);
DOT 1 (-5850 9200);
DOT 1 (-7100 10100);
DOT 1 (-7100 10400);
DOT 1 (-7050 10500);
DOT 1 (-6950 10800);
DOT 1 (-6900 10800);
DOT 1 (-9950 5850);
DOT 1 (-9950 6100);
DOT 1 (-10000 6000);
DOT 1 (-10000 5750);
DOT 1 (-3700 5550);
DOT 1 (-8900 10500);
FORCENOTE
EEPROM
(-7950 7150) 0;
DISPLAY LEFT (-7950 7150);
DISPLAY 4.914894 (-7950 7150);
FORCENOTE
EEPROM_ADDR : 101 0000 , 0X50
(-8450 6250) 0;
DISPLAY LEFT (-8450 6250);
DISPLAY 1.595745 (-8450 6250);
FORCENOTE
EUI&S/N_ADDR: 101 1000 , 0X58
(-8450 6100) 0;
DISPLAY LEFT (-8450 6100);
DISPLAY 1.595745 (-8450 6100);
FORCENOTE
SEC_EEPROM_ADDR: 101 0001 , 0X51
(-7700 5000) 0;
DISPLAY LEFT (-7700 5000);
DISPLAY 1.595745 (-7700 5000);
FORCENOTE
PCA9546A_I2C_SWITCH
(-8650 12050) 0;
DISPLAY LEFT (-8650 12050);
DISPLAY 3.936170 (-8650 12050);
FORCENOTE
MP PHASE: DNP J9.
(-10500 8450) 0;
DISPLAY LEFT (-10500 8450);
DISPLAY 1.574468 (-10500 8450);
FORCENOTE
RSVD FOR DBG
(-10500 8600) 0;
DISPLAY LEFT (-10500 8600);
DISPLAY 1.574468 (-10500 8600);
FORCENOTE
ADDR:0X70
(-8300 9050) 0;
DISPLAY LEFT (-8300 9050);
DISPLAY 1.595745 (-8300 9050);
FORCENOTE
1&2 : U7  EEPROM, EEPROM_WP = DISABLE
(-2450 6200) 0;
DISPLAY LEFT (-2450 6200);
DISPLAY 1.255319 (-2450 6200);
FORCENOTE
3&4 : U19 EEPROM, EEPROM_WP = DISABLE
(-2450 6100) 0;
DISPLAY LEFT (-2450 6100);
DISPLAY 1.255319 (-2450 6100);
QUIT
